G04 ================== begin FILE IDENTIFICATION RECORD ==================*
G04 Layout Name:  F:/<user>/2022/FB/R4006-TIMING/brd/gerber-3/R4006-B0001-02_R01.brd*
G04 Film Name:    R4006-B0001-02_R01_L06*
G04 File Format:  Gerber RS274X*
G04 File Origin:  Cadence Allegro 17.2-S079*
G04 Origin Date:  Fri Feb 25 18:14:43 2022*
G04 *
G04 Layer:  ETCH/L06_VCC2*
G04 Layer:  PIN/L06_VCC2*
G04 Layer:  VIA CLASS/L06_VCC2*
G04 Layer:  MANUFACTURING/L06_VCC2*
G04 Layer:  MANUFACTURING/CELESTICA_LEGEND*
G04 *
G04 Offset:    (0.00 0.00)*
G04 Mirror:    No*
G04 Mode:      Negative*
G04 Rotation:  0*
G04 FullContactRelief:  No*
G04 UndefLineWidth:     6.00*
G04 ================== end FILE IDENTIFICATION RECORD ====================*
%FSLAX55Y55*MOIN*%
%IR0*IPPOS*OFA0.00000B0.00000*MIA0B0*SFA1.00000B1.00000*%
%ADD12C,.02*%
%ADD10C,.03*%
%ADD13C,.032*%
%ADD15C,.033*%
%ADD19C,.026*%
%ADD21C,.018*%
%ADD20C,.028*%
%ADD16C,.082*%
%ADD29C,.056*%
%ADD18C,.039*%
%ADD11C,.086*%
%ADD25C,.099*%
%ADD22C,.102*%
%ADD14C,.15*%
%ADD27C,.143*%
%ADD23C,.125*%
%ADD28O,.074X.047*%
%ADD17O,.086X.047*%
%ADD24C,.189*%
%AMMACRO26*
4,1,18,.0371,.0272,
.04126,.020344,
.044166,.012871,
.04573,.005006,
.045904,-.003011,
.044684,-.010936,
.042106,-.01853,
.038249,-.02556,
.0371,-.0272,
.04067,-.03077,
.045395,-.02324,
.048741,-.015004,
.050606,-.006313,
.050934,.002571,
.049713,.011376,
.046983,.019836,
.042824,.027693,
.04067,.03077,
.0371,.0272,
270.*
4,1,18,.0272,-.0371,
.020344,-.04126,
.012871,-.044166,
.005006,-.04573,
-.003011,-.045904,
-.010936,-.044684,
-.01853,-.042106,
-.02556,-.038249,
-.0272,-.0371,
-.03077,-.04067,
-.02324,-.045395,
-.015004,-.048741,
-.006313,-.050606,
.002571,-.050934,
.011376,-.049713,
.019836,-.046983,
.027693,-.042824,
.03077,-.04067,
.0272,-.0371,
270.*
4,1,18,-.0371,-.0272,
-.04126,-.020344,
-.044166,-.012871,
-.04573,-.005006,
-.045904,.003011,
-.044684,.010936,
-.042106,.01853,
-.038249,.02556,
-.0371,.0272,
-.04067,.03077,
-.045395,.02324,
-.048741,.015004,
-.050606,.006313,
-.050934,-.002571,
-.049713,-.011376,
-.046983,-.019836,
-.042824,-.027693,
-.04067,-.03077,
-.0371,-.0272,
270.*
4,1,18,-.0272,.0371,
-.020344,.04126,
-.012871,.044166,
-.005006,.04573,
.003011,.045904,
.010936,.044684,
.01853,.042106,
.02556,.038249,
.0272,.0371,
.03077,.04067,
.02324,.045395,
.015004,.048741,
.006313,.050606,
-.002571,.050934,
-.011376,.049713,
-.019836,.046983,
-.027693,.042824,
-.03077,.04067,
-.0272,.0371,
270.*
%
%ADD26MACRO26*%
%ADD30C,.01*%
%ADD31C,.005*%
%ADD32C,.006*%
%ADD45R,.07002X.03002*%
%ADD49R,.07004X.03002*%
%ADD42R,.07002X.03004*%
%ADD46R,.07004X.03004*%
%ADD44R,.03004X.07004*%
%ADD38C,.40006*%
%ADD35C,.14006*%
%ADD40R,.02802X.06002*%
%ADD33C,.12406*%
%ADD47R,.06004X.02802*%
%ADD43R,.06002X.02804*%
%ADD41R,.02802X.06004*%
%ADD36R,.06004X.02804*%
%ADD37C,.28406*%
%ADD48O,.02606X.06543*%
%ADD39C,.16806*%
%ADD34C,.27606*%
G75*
%LPD*%
G75*
G36*
G01X-10000Y-10000D02*
X670039D01*
Y447598D01*
X-10000D01*
Y-10000D01*
G37*
%LPC*%
G75*
G36*
G01X88001Y190171D02*
X87921Y190037D01*
G03X87498Y188501I2579J-1537D01*
G01Y188500D01*
G03X90500Y185498I3002J0D01*
G01X90501D01*
G03X92037Y185921I-1J3002D01*
G01X92171Y186001D01*
X166000Y112172D01*
Y57666D01*
G03X154795Y43012I3980J-14654D01*
G01Y25717D01*
X139299D01*
Y46260D01*
G03X127362Y58197I-11937J0D01*
G01X122464D01*
X122429Y58353D01*
G03X116571I-2929J-659D01*
G01X116536Y58197D01*
X62992D01*
G03X51055Y46260I0J-11937D01*
G01Y25717D01*
X38874D01*
G02X38611Y26418I0J400D01*
G03X43330Y36809I-9083J10392D01*
G01Y36811D01*
G03X15726I-13802J0D01*
G01Y36809D01*
G03X20445Y26418I13802J1D01*
G02X20182Y25717I-263J-301D01*
G01X8000D01*
Y55061D01*
G03X12541Y61260I-1961J6199D01*
G03X8000Y67459I-6502J0D01*
G01Y75061D01*
G03Y87459I-1961J6199D01*
G01Y112147D01*
G03Y124545I-1961J6199D01*
G01Y132147D01*
G03Y144545I-1961J6199D01*
G01Y169234D01*
G03Y181632I-1961J6199D01*
G01Y189234D01*
G03Y201632I-1961J6199D01*
G01Y226321D01*
G03Y238719I-1961J6199D01*
G01Y246321D01*
G03Y258719I-1961J6199D01*
G01Y429598D01*
X50144D01*
X52500Y427242D01*
Y387500D01*
G03X53086Y386086I1999J0D01*
G01X56000Y383172D01*
Y291600D01*
G03Y286400I1499J-2600D01*
G01Y229100D01*
G03Y223900I1499J-2600D01*
G01Y223000D01*
G03X56586Y221586I1999J0D01*
G01X88001Y190171D01*
G37*
G36*
G01X93034Y243475D02*
G03X94695Y243977I-1J3002D01*
G01X223000Y115672D01*
Y61214D01*
X222844Y61179D01*
G03Y55321I655J-2929D01*
G01X223000Y55286D01*
Y40899D01*
G03X213260Y29331I2000J-11568D01*
G01Y26200D01*
X185165D01*
Y43012D01*
G03X170000Y58197I-15185J0D01*
G01Y113000D01*
G03X169414Y114414I-1999J0D01*
G01X60000Y223828D01*
Y224838D01*
X60031Y224887D01*
G03X60502Y226500I-2530J1614D01*
G03X60000Y228162I-3002J0D01*
G01Y287338D01*
G03Y290662I-2500J1662D01*
G01Y383172D01*
X61328Y384500D01*
X73672D01*
X76000Y382172D01*
Y363000D01*
G03X76586Y361586I1999J0D01*
G01X88500Y349672D01*
Y251000D01*
G03X89086Y249586I1999J0D01*
G01X90529Y248143D01*
X90450Y248009D01*
G03X90030Y246478I2582J-1531D01*
G01Y246477D01*
G03X93032Y243475I3002J0D01*
G01X93034D01*
G37*
G36*
G01X58756Y429598D02*
X601814D01*
X604000Y427412D01*
Y393000D01*
X597000D01*
G03X595586Y392414I0J-1999D01*
G01X581587Y378415D01*
X581463Y378467D01*
G03X580300Y378702I-1164J-2767D01*
G03X577298Y375700I0J-3002D01*
G03X578000Y373771I3001J0D01*
G01Y368845D01*
G03X577098Y366700I2099J-2145D01*
G03X577944Y364611I3002J0D01*
G01X578000Y364553D01*
Y363744D01*
X577950Y363687D01*
G03Y359713I2249J-1987D01*
G01X578000Y359656D01*
Y358631D01*
X577956Y358576D01*
G03X577298Y356700I2345J-1876D01*
G03X578000Y354771I3001J0D01*
G01Y337828D01*
X566586Y326414D01*
G03X566000Y325000I1413J-1414D01*
G01Y320828D01*
X563172Y318000D01*
X552828D01*
X549500Y321328D01*
Y370500D01*
G03X548914Y371914I-1999J0D01*
G01X531414Y389414D01*
G03X530000Y390000I-1414J-1413D01*
G01X529838D01*
X529785Y390119D01*
G03X527500Y391602I-2285J-1019D01*
G03X525165Y390000I0J-2503D01*
G01X467328D01*
X462424Y394904D01*
G03X461010Y395490I-1414J-1413D01*
G01X456248D01*
G03X451752I-2248J-1991D01*
G01X421966D01*
G03X416334I-2816J-1040D01*
G01X412466D01*
G03X406834I-2816J-1040D01*
G01X322230D01*
G03X320816Y394904I0J-1999D01*
G01X317392Y391480D01*
X170650D01*
G03X169236Y390894I0J-1999D01*
G01X166842Y388500D01*
X160693D01*
G03X155107I-2793J-1100D01*
G01X152993D01*
G03X149207I-1893J-2201D01*
G01X141224D01*
G03X135776I-2724J-1000D01*
G01X60500D01*
G03X59086Y387914I0J-1999D01*
G01X58000Y386828D01*
X56500Y388328D01*
Y427342D01*
X58756Y429598D01*
G37*
G36*
G01X456230Y391490D02*
X460182D01*
X465086Y386586D01*
G03X466500Y386000I1414J1413D01*
G01X529172D01*
X545500Y369672D01*
Y320500D01*
G03X546086Y319086I1999J0D01*
G01X550586Y314586D01*
G03X552000Y314000I1414J1413D01*
G01X564000D01*
G03X565414Y314586I0J1999D01*
G01X569414Y318586D01*
G03X570000Y320000I-1413J1414D01*
G01Y324172D01*
X579733Y333905D01*
G02X580414Y333659I283J-283D01*
G03X588779Y326046I8365J789D01*
G03X597182Y334449I0J8403D01*
G01Y367682D01*
X597175Y367844D01*
G03X584911Y374978I-8396J-325D01*
G02X584444Y375616I-184J355D01*
G01X597828Y389000D01*
X605172D01*
X611500Y382672D01*
Y328328D01*
X604172Y321000D01*
X589500D01*
G03X588086Y320414I0J-1999D01*
G01X577586Y309914D01*
G03X577000Y308500I1413J-1414D01*
G01Y238924D01*
G03X575898Y236600I1900J-2324D01*
G03X576080Y235571I3002J0D01*
G01X576123Y235451D01*
X570172Y229500D01*
X568803D01*
G03X564597I-2103J-2001D01*
G01X561984D01*
G03X557016I-2484J-1500D01*
G01X555593D01*
G03X553122Y230881I-2471J-1520D01*
G03X550961Y229916I0J-2902D01*
G02X550360Y229923I-297J267D01*
G03X548158Y230935I-2202J-1890D01*
G03X545654Y229500I0J-2902D01*
G01X534328D01*
X531500Y232328D01*
Y254707D01*
G03Y260253I-1150J2773D01*
G01Y282536D01*
X531656Y282571D01*
G03Y288429I-655J2929D01*
G01X531500Y288464D01*
Y368000D01*
G03X530914Y369414I-1999J0D01*
G01X521414Y378914D01*
G03X520000Y379500I-1414J-1413D01*
G01X228831D01*
G03X226000Y381502I-2831J-1001D01*
G03X223891Y380636I0J-3001D01*
G02X223609I-141J142D01*
G03X221500Y381502I-2109J-2135D01*
G03X218669Y379500I0J-3003D01*
G01X191000D01*
G03X189586Y378914I0J-1999D01*
G01X178672Y368000D01*
X134500D01*
G03X133086Y367414I0J-1999D01*
G01X124172Y358500D01*
X96500D01*
G03X95086Y357914I0J-1999D01*
G01X90500Y353328D01*
X85784Y358044D01*
X85890Y358183D01*
G03X86502Y360000I-2391J1817D01*
G03X83500Y363002I-3002J0D01*
G03X81683Y362390I0J-3003D01*
G01X81544Y362284D01*
X80000Y363828D01*
Y383000D01*
G03X79613Y384182I-1999J0D01*
G02X79775Y384500I162J118D01*
G01X80294D01*
X80313Y384322D01*
G03X85287I2487J279D01*
G01X85306Y384500D01*
X104398D01*
Y379598D01*
X113402D01*
Y384500D01*
X148824D01*
G03X153376I2276J1799D01*
G01X157124D01*
X157148Y384494D01*
G03X157900Y384398I753J2906D01*
G03X158652Y384494I-1J3002D01*
G01X158676Y384500D01*
X167670D01*
G03X169084Y385086I0J1999D01*
G01X171478Y387480D01*
X318220D01*
G03X319634Y388066I0J1999D01*
G01X321993Y390425D01*
G02X322631Y390325I282J-283D01*
G03X325300Y388698I2669J1376D01*
G03X328277Y391316I0J3002D01*
G01X328300Y391490D01*
X337495D01*
X337512Y391309D01*
G03X343488I2988J291D01*
G01X343505Y391490D01*
X409149D01*
X409165Y391487D01*
G03X409650Y391448I482J2963D01*
G03X410135Y391487I3J3002D01*
G01X410151Y391490D01*
X418649D01*
X418665Y391487D01*
G03X419150Y391448I482J2963D01*
G03X419635Y391487I3J3002D01*
G01X419651Y391490D01*
X429082D01*
X429126Y391349D01*
G03X434674I2774J850D01*
G01X434718Y391490D01*
X451770D01*
G03X456230I2230J2011D01*
G37*
G36*
G01X527500Y301724D02*
G03Y296276I1000J-2724D01*
G01Y258424D01*
X527491Y258394D01*
G03X527348Y257480I2859J-915D01*
G03X527491Y256566I3002J1D01*
G01X527500Y256536D01*
Y244500D01*
X488914D01*
X486500Y246914D01*
Y281000D01*
G03X486207Y281707I-999J0D01*
G01X462207Y305707D01*
G03X461500Y306000I-707J-706D01*
G01X459464D01*
X459429Y306156D01*
G03X453571I-2929J-655D01*
G01X453536Y306000D01*
X416500D01*
G03X415793Y305707I0J-999D01*
G01X413541Y303455D01*
X413441Y303469D01*
G03X413000Y303502I-444J-2969D01*
G03X409998Y300500I0J-3002D01*
G03X410031Y300059I3002J3D01*
G01X410045Y299959D01*
X406793Y296707D01*
G03X406500Y296000I706J-707D01*
G01Y293012D01*
G03Y290388I2699J-1312D01*
G01Y287383D01*
G03X406298Y286300I2800J-1083D01*
G03X406500Y285217I3002J0D01*
G01Y282801D01*
G03Y279799I2601J-1501D01*
G01Y248414D01*
X389588Y231502D01*
X372585D01*
X370498Y229415D01*
Y216000D01*
X369666D01*
G03X369560Y216002I-110J-3000D01*
G03X369454Y216000I4J-3002D01*
G01X367106D01*
G03X367000Y216002I-110J-3000D01*
G03X366894Y216000I4J-3002D01*
G01X364606D01*
G03X364500Y216002I-110J-3000D01*
G03X364394Y216000I4J-3002D01*
G01X354914D01*
X352500Y218414D01*
Y227261D01*
G03X353502Y229500I-2001J2239D01*
G03X353063Y231062I-3002J-1D01*
G03X354002Y233243I-2063J2181D01*
G01Y233245D01*
G03X353342Y235122I-3002J-1D01*
G03X354002Y237000I-2342J1878D01*
G03X352500Y239600I-3001J0D01*
G01Y251586D01*
X360707Y259793D01*
G03X361000Y260500I-706J707D01*
G01Y261394D01*
G03X361002Y261500I-3000J110D01*
G03X361000Y261606I-3002J-4D01*
G01Y288500D01*
G03X360707Y289207I-999J0D01*
G01X312207Y337707D01*
G03X311500Y338000I-707J-706D01*
G01X297804D01*
G03X297700Y338002I-108J-2900D01*
G03X297596Y338000I4J-2902D01*
G01X175500D01*
G03X174793Y337707I0J-999D01*
G01X156541Y319455D01*
X156441Y319469D01*
G03X156000Y319502I-444J-2969D01*
G03X152998Y316500I0J-3002D01*
G03X153031Y316059I3002J3D01*
G01X153045Y315959D01*
X150820Y313734D01*
X150695Y313788D01*
G03X149500Y314036I-1195J-2755D01*
G03X146498Y311034I0J-3002D01*
G01Y311030D01*
G03X146517Y310695I3002J2D01*
G02X146120Y310250I-397J-45D01*
G01X138630D01*
G03X137923Y309957I0J-999D01*
G01X136453Y308487D01*
G03X136160Y307780I706J-707D01*
G01Y299074D01*
X130160Y293074D01*
G03X128939Y291866I1339J-2575D01*
G01X128925Y291839D01*
X110293Y273207D01*
G03X110000Y272500I706J-707D01*
G01Y237866D01*
G03X109793Y237707I500J-866D01*
G01X109086Y237000D01*
X107328D01*
X92500Y251828D01*
Y349672D01*
X97328Y354500D01*
X125000D01*
G03X126414Y355086I0J1999D01*
G01X135328Y364000D01*
X179500D01*
G03X180914Y364586I0J1999D01*
G01X191828Y375500D01*
X221394D01*
G03X221500Y375498I110J3000D01*
G03X221606Y375500I-4J3002D01*
G01X225894D01*
G03X226000Y375498I110J3000D01*
G03X226106Y375500I-4J3002D01*
G01X328536D01*
X328571Y375344D01*
G03X334429I2929J655D01*
G01X334464Y375500D01*
X335536D01*
X335571Y375344D01*
G03X338500Y372998I2929J655D01*
G03X340250Y373561I0J3001D01*
G03X342000Y372998I1750J2438D01*
G03X344929Y375344I0J3001D01*
G01X344964Y375500D01*
X376508D01*
X376535Y375331D01*
G03X382465I2965J469D01*
G01X382492Y375500D01*
X501536D01*
X501571Y375344D01*
G03X507429I2929J655D01*
G01X507464Y375500D01*
X519172D01*
X527500Y367172D01*
Y321900D01*
G03Y315900I100J-3000D01*
G01Y301724D01*
G37*
G36*
G01X361147Y213998D02*
G02X361541Y213528I0J-400D01*
G03X361494Y213000I2959J-529D01*
G03X364500Y209994I3006J0D01*
G03X365754Y210268I0J3007D01*
G03X367000Y209997I1247J2732D01*
G03X368279Y210283I0J3003D01*
G03X369560Y209996I1281J2717D01*
G01X369561D01*
G03X370035Y210034I-2J3004D01*
G02X370498Y209639I63J-395D01*
G01Y177502D01*
X364585D01*
X360998Y173915D01*
Y140085D01*
X363998Y137085D01*
Y93402D01*
X361098D01*
Y90598D01*
X363998D01*
Y77585D01*
X371085Y70498D01*
X377399D01*
G03X381601I2101J2002D01*
G01X421267D01*
G03X422999Y69948I1732J2452D01*
G01X423001D01*
G03X424733Y70498I0J3002D01*
G01X478000D01*
X478022Y70323D01*
G03X483978I2978J377D01*
G01X484000Y70498D01*
X551415D01*
X556502Y75585D01*
Y101415D01*
X492415Y165502D01*
X451724D01*
G02X451363Y166072I1J400D01*
G03X451487Y166626I-1178J555D01*
G01Y166627D01*
G03X450633Y167850I-1303J0D01*
G01X450502Y167898D01*
Y169293D01*
X450633Y169341D01*
G03Y171787I-449J1223D01*
G01X450502Y171835D01*
Y172415D01*
X448002Y174915D01*
Y183415D01*
X446846Y184571D01*
G02X446922Y185196I283J283D01*
G03X447550Y186309I-674J1114D01*
G01Y186311D01*
G03X446248Y187614I-1303J0D01*
G01X443803D01*
X442915Y188502D01*
X419415D01*
X395002Y212915D01*
Y220670D01*
G03Y226330I-1002J2830D01*
G01Y226915D01*
X392114Y229803D01*
G02X392115Y230369I283J283D01*
G03X392958Y231990I-2116J2130D01*
G01X392969Y232053D01*
X405019Y244103D01*
G03X406383Y245452I-1319J2697D01*
G01X406397Y245481D01*
X408502Y247585D01*
Y295585D01*
X411096Y298179D01*
G03X413000Y297498I1904J2321D01*
G03X416002Y300500I0J3002D01*
G03X415321Y302404I-3002J0D01*
G01X416915Y303998D01*
X433722D01*
G03X435142Y303641I1420J2645D01*
G01X435144D01*
G03X436564Y303998I0J3002D01*
G01X449340D01*
G03X450999Y303498I1659J2502D01*
G01X451001D01*
G03X452612Y303967I0J3002D01*
G01X452661Y303998D01*
X453900D01*
G03X459100I2600J1503D01*
G01X461085D01*
X484498Y280585D01*
Y246085D01*
X488085Y242498D01*
X495059D01*
G03X497099Y241698I2040J2202D01*
G01X497101D01*
G03X499141Y242498I0J3002D01*
G01X510059D01*
G03X512099Y241698I2040J2202D01*
G01X512101D01*
G03X514141Y242498I0J3002D01*
G01X527500D01*
Y231500D01*
G03X528086Y230086I1999J0D01*
G01X532086Y226086D01*
G03X533500Y225500I1414J1413D01*
G01X546742D01*
G03X549574I1416J2532D01*
G01X551613D01*
G03X554631I1509J2480D01*
G01X558026D01*
G03X560974I1474J2501D01*
G01X564597D01*
G03X568803I2103J2001D01*
G01X571000D01*
G03X572414Y226086I0J1999D01*
G01X580242Y233914D01*
X580270Y233929D01*
G03X581902Y236600I-1370J2671D01*
G03X581000Y238745I-3001J0D01*
G01Y307672D01*
X590328Y317000D01*
X605000D01*
G03X606414Y317586I0J1999D01*
G01X614914Y326086D01*
G03X615500Y327500I-1413J1414D01*
G01Y383500D01*
G03X614914Y384914I-1999J0D01*
G01X608000Y391828D01*
Y427112D01*
X610486Y429598D01*
X631519D01*
G02X631759Y428878I0J-400D01*
G03X626236Y417835I8280J-11044D01*
G03X640039Y404032I13803J0D01*
G03X651312Y409871I-1J13803D01*
G02X652039Y409641I327J-230D01*
G01Y291199D01*
G03X647243Y282679I5172J-8522D01*
G01Y241437D01*
G03X652039Y232916I9968J0D01*
G01Y73548D01*
G02X651312Y73318I-400J0D01*
G03X640039Y79156I-11273J-7965D01*
G03X626236Y65354I0J-13803D01*
G03X627899Y58787I13803J1D01*
G02X627547Y58197I-352J-190D01*
G01X316142D01*
G03X304205Y46260I0J-11937D01*
G01Y26200D01*
X236740D01*
Y29331D01*
G03X227000Y40899I-11740J0D01*
G01Y116500D01*
G03X226414Y117914I-1999J0D01*
G01X112000Y232328D01*
Y237083D01*
X112002Y237085D01*
Y272085D01*
X127415Y287498D01*
X127500D01*
G03X130502Y290500I0J3002D01*
G01Y290585D01*
X138162Y298245D01*
Y307365D01*
X139045Y308248D01*
X148165D01*
X148227Y308311D01*
X148352Y308260D01*
G03X149497Y308032I1148J2774D01*
G01X149500D01*
G03X152502Y311034I0J3002D01*
G01Y311037D01*
G03X152274Y312183I-3002J-2D01*
G01X152223Y312307D01*
X154092Y314176D01*
X154231Y314075D01*
G03X156000Y313498I1770J2425D01*
G03X159002Y316500I0J3002D01*
G03X158321Y318404I-3002J0D01*
G01X175915Y335998D01*
X218121D01*
G03X219198Y335798I1077J2802D01*
G01X219202D01*
G03X220279Y335998I0J3002D01*
G01X311085D01*
X321216Y325868D01*
X321123Y325732D01*
G03X320898Y325000I1078J-732D01*
G03X322200Y323698I1302J0D01*
G03X322932Y323923I0J1303D01*
G01X323068Y324016D01*
X358998Y288085D01*
Y260915D01*
X350498Y252415D01*
Y239964D01*
X350342Y239929D01*
G03X347998Y237000I658J-2929D01*
G03X348658Y235122I3002J0D01*
G03X347998Y233245I2342J-1878D01*
G01Y233243D01*
G03X348436Y231683I3002J1D01*
G03X347496Y229500I2065J-2183D01*
G03X350498Y226496I3004J0D01*
G01Y217585D01*
X354085Y213998D01*
X361147D01*
G37*
G36*
G01X485662Y163500D02*
X491586D01*
X493221Y161865D01*
G03X494830Y160235I2779J1134D01*
G01X494866Y160220D01*
X499998Y155088D01*
Y155005D01*
G03X503005Y151998I3002J-5D01*
G01X503088D01*
X511530Y143556D01*
X511541Y143493D01*
G03X513993Y141041I2959J507D01*
G01X514056Y141030D01*
X530498Y124588D01*
Y124505D01*
G03X533505Y121498I3002J-5D01*
G01X533588D01*
X554500Y100586D01*
Y76414D01*
X550586Y72500D01*
X483402D01*
G03X478598I-2402J-1799D01*
G01X371914D01*
X366000Y78414D01*
Y90598D01*
X367102D01*
Y93402D01*
X366000D01*
Y136500D01*
X393000D01*
G03X393707Y136793I0J999D01*
G01X394721Y137807D01*
X394825Y137788D01*
G03X395067Y137765I244J1279D01*
G03X396369Y139067I0J1302D01*
G03X396346Y139309I-1302J-2D01*
G01X396327Y139413D01*
X398207Y141293D01*
G03X398500Y142000I-706J707D01*
G01Y145640D01*
X399004D01*
G03Y148244I0J1302D01*
G01X398500D01*
Y153514D01*
X399004D01*
G03Y156118I0J1302D01*
G01X398500D01*
Y161388D01*
X399004D01*
G03X400306Y162690I0J1302D01*
G03X400268Y163004I-1302J2D01*
G02X400656Y163500I388J96D01*
G01X482338D01*
G03X485662I1662J2500D01*
G37*
G36*
G01X375912Y175500D02*
X395086D01*
X396500Y174086D01*
Y171866D01*
X395067D01*
G03Y169262I0J-1302D01*
G01X396500D01*
Y163992D01*
X395067D01*
G03Y161388I0J-1302D01*
G01X396500D01*
Y156118D01*
X395067D01*
G03Y153514I0J-1302D01*
G01X396500D01*
Y148244D01*
X395067D01*
G03Y145640I0J-1302D01*
G01X396500D01*
Y142414D01*
X392586Y138500D01*
X365414D01*
X363000Y140914D01*
Y152838D01*
G03Y156162I-2500J1662D01*
G01Y173086D01*
X363512Y173598D01*
X363595D01*
G03X366393Y175500I5J3002D01*
G01X373288D01*
G03X375912I1312J2699D01*
G37*
G36*
G01X392442Y226644D02*
G02X392376Y226025I-283J-283D01*
G03X390998Y223500I1624J-2525D01*
G03X393000Y220669I3003J0D01*
G01Y212500D01*
G03X393293Y211793I999J0D01*
G01X418293Y186793D01*
G03X419000Y186500I707J706D01*
G01X441007D01*
X441009Y186301D01*
G03X442311Y185008I1302J9D01*
G01X443578D01*
X445310Y183276D01*
G03X444946Y182374I938J-903D01*
G03X445860Y181131I1302J0D01*
G01X446000Y181087D01*
Y179724D01*
X445860Y179680D01*
G03Y177194I388J-1243D01*
G01X446000Y177150D01*
Y174500D01*
G03X446293Y173793I999J0D01*
G01X448500Y171586D01*
Y165500D01*
X408418D01*
G02X408057Y166071I0J400D01*
G03X408182Y166627I-1178J557D01*
G03X406879Y167930I-1303J0D01*
G01X402942D01*
G03X401640Y166627I0J-1302D01*
G03X401764Y166071I1302J-1D01*
G02X401403Y165500I-361J-171D01*
G01X398500D01*
Y169262D01*
X399004D01*
G03Y171866I0J1302D01*
G01X398500D01*
Y174500D01*
G03X398207Y175207I-999J0D01*
G01X396207Y177207D01*
G03X395500Y177500I-707J-706D01*
G01X381150D01*
X381100Y177625D01*
G03X378500I-1300J-525D01*
G01X378450Y177500D01*
X372500D01*
Y210026D01*
X372660Y210059D01*
G03Y215941I-599J2941D01*
G01X372500Y215974D01*
Y228586D01*
X372944Y229030D01*
X373007Y229041D01*
G03X374162Y229500I-507J2959D01*
G01X382894D01*
G03X383000Y229498I110J3000D01*
G03X383106Y229500I-4J3002D01*
G01X389586D01*
X392442Y226644D01*
G37*
%LPD*%
G75*
G36*
G01X600696Y115350D02*
G02X617500Y124503I16804J-10849D01*
G02X637503Y104500I0J-20003D01*
G02X636283Y97621I-20004J0D01*
G02X636500Y96501I-2783J-1120D01*
G01Y96500D01*
G02X634273Y93601I-3000J0D01*
G02X617500Y84497I-16773J10899D01*
G02X597497Y104500I0J20003D01*
G02X598437Y110560I20003J0D01*
G02X597846Y112349I2413J1789D01*
G01Y112350D01*
G02X600696Y115350I3004J0D01*
G37*
G36*
G01X316747Y85237D02*
X314763Y83253D01*
X310516Y87500D01*
X312500Y89484D01*
X316747Y85237D01*
G37*
G36*
G01X402942Y149576D02*
G02Y152182I0J1303D01*
G01X406879D01*
G02Y149576I0J-1303D01*
G01X402942D01*
G37*
G36*
G01X446248Y141702D02*
G02Y144308I0J1303D01*
G01X450185D01*
G02Y141702I0J-1303D01*
G01X446248D01*
G37*
G36*
G01X469870Y145640D02*
G02Y148244I0J1302D01*
G01X473807D01*
G02Y145640I0J-1302D01*
G01X469870D01*
G37*
G36*
G01X461996Y129890D02*
G02Y132496I0J1303D01*
G01X465933D01*
G02Y129890I0J-1303D01*
G01X461996D01*
G37*
G36*
G01X387193Y165324D02*
G02Y167930I0J1303D01*
G01X391130D01*
G02Y165324I0J-1303D01*
G01X387193D01*
G37*
G36*
G01Y149576D02*
G02Y152182I0J1303D01*
G01X391130D01*
G02Y149576I0J-1303D01*
G01X387193D01*
G37*
G36*
G01Y141702D02*
G02Y144308I0J1303D01*
G01X391130D01*
G02Y141702I0J-1303D01*
G01X387193D01*
G37*
G36*
G01Y157450D02*
G02Y160056I0J1303D01*
G01X391130D01*
G02Y157450I0J-1303D01*
G01X387193D01*
G37*
G54D45*
X353065Y104707D03*
X439251Y116599D03*
X455731Y122167D03*
G54D49*
X403250Y116099D03*
G54D42*
X281801Y198700D03*
G54D46*
X343400Y108500D03*
G54D44*
X240508Y71500D03*
X337500Y117800D03*
X284500Y185900D03*
G54D38*
X599000Y209400D03*
G54D35*
X126067Y184043D03*
X286067Y104043D03*
G54D40*
X365101Y189959D03*
X345301Y191499D03*
G54D33*
X143567Y106043D03*
X146067Y268043D03*
X268567Y255943D03*
Y112143D03*
G54D47*
X324310Y190299D03*
G54D43*
X283455Y76300D03*
X268307D03*
G54D41*
X619961Y226074D03*
X295835Y46500D03*
X280087Y36900D03*
X295835D03*
X264339D03*
G54D36*
X71900Y357500D03*
X248622Y76300D03*
G54D37*
X494094Y412008D03*
X255906D03*
X494094Y309646D03*
X255906D03*
G54D48*
X473807Y137098D03*
G54D39*
X634055Y367519D03*
Y334449D03*
G54D34*
X29528Y373031D03*
G54D10*
X8878Y21717D03*
X4878D03*
X4000Y25619D03*
Y29619D03*
Y33619D03*
Y37619D03*
Y41619D03*
Y45619D03*
Y49619D03*
Y281619D03*
Y285619D03*
Y289619D03*
Y293619D03*
Y297619D03*
Y301619D03*
Y305619D03*
Y309619D03*
Y313619D03*
Y337619D03*
Y341619D03*
Y345619D03*
Y349619D03*
Y353619D03*
Y357619D03*
Y361619D03*
Y365619D03*
Y369619D03*
Y373619D03*
Y377619D03*
Y381619D03*
Y385619D03*
Y389619D03*
Y393619D03*
Y397619D03*
Y401619D03*
Y405619D03*
Y409619D03*
Y413619D03*
Y417619D03*
Y421619D03*
Y425619D03*
Y429619D03*
X4413Y433598D03*
X8413D03*
X24878Y21717D03*
X20878D03*
X16878D03*
X12878D03*
X12413Y433598D03*
X16413D03*
X20413D03*
X24413D03*
X28413D03*
X44878Y21717D03*
X40878D03*
X36878D03*
X32878D03*
X28878D03*
X32413Y433598D03*
X36413D03*
X40413D03*
X44413D03*
X55055Y25073D03*
X52878Y21717D03*
X48878D03*
X55055Y41073D03*
Y37073D03*
Y33073D03*
Y29073D03*
X61463Y54048D03*
X57859Y52313D03*
X55558Y49041D03*
X55055Y45073D03*
X48413Y433598D03*
X52413D03*
X56413D03*
X60413D03*
X77460Y54197D03*
X73460D03*
X69460D03*
X65460D03*
X76100Y154400D03*
X75950Y164200D03*
X79248Y266100D03*
X73600Y252500D03*
X67000Y283100D03*
X68600Y274000D03*
X75500Y282500D03*
X63800Y274000D03*
X76700Y357500D03*
X67100D03*
X70500Y419000D03*
X75580Y419004D03*
X68413Y433598D03*
X72413D03*
X76413D03*
X80413D03*
X64413D03*
X97460Y54197D03*
X93460D03*
X89460D03*
X85460D03*
X81460D03*
X86800Y230000D03*
X85600Y263700D03*
X98000Y420000D03*
X90000Y420500D03*
X85500D03*
X84413Y433598D03*
X88413D03*
X92413D03*
X96413D03*
X113460Y54197D03*
X109460D03*
X105460D03*
X101460D03*
X112880Y73020D03*
X113700Y382500D03*
X104100D03*
X104413Y433598D03*
X108413D03*
X112413D03*
X100413D03*
X132920Y51926D03*
X129450Y53917D03*
X125460Y54197D03*
X121460D03*
X117460D03*
X126000Y67000D03*
Y62000D03*
X131500Y290500D03*
X116413Y433598D03*
X120413D03*
X124413D03*
X128413D03*
X132413D03*
X135299Y24509D03*
X150163Y21717D03*
X146163D03*
X142163D03*
X138163D03*
X135299Y28509D03*
Y32509D03*
Y36509D03*
Y40509D03*
Y44509D03*
X134977Y48496D03*
X148500Y62500D03*
X139500D03*
X144000D03*
X138500Y75000D03*
X145900Y75200D03*
X142070Y77900D03*
X142000Y69535D03*
X136000Y290500D03*
X138250Y372250D03*
X148500Y376000D03*
X138500Y387500D03*
X140413Y433598D03*
X144413D03*
X148413D03*
X136413D03*
X158163Y21717D03*
X154163D03*
X158795Y25667D03*
Y41667D03*
Y37667D03*
Y33667D03*
Y29667D03*
X160736Y49309D03*
X159112Y45654D03*
X163543Y52159D03*
X151840Y79935D03*
X153500Y390500D03*
X163300Y382900D03*
X151100Y386300D03*
X167100Y405600D03*
X152100Y399300D03*
X151530Y406300D03*
X153150Y394590D03*
X160600Y417400D03*
X152200Y416300D03*
X152413Y433598D03*
X156413D03*
X160413D03*
X164413D03*
X183170Y56390D03*
X180341Y47225D03*
X178196Y50601D03*
X180620Y77890D03*
X180390Y70720D03*
X180910Y63390D03*
X168413Y433598D03*
X172413D03*
X176413D03*
X180413D03*
X184413D03*
X191535Y28900D03*
X201950Y29050D03*
X191535Y41200D03*
X198135Y36500D03*
X195000Y54550D03*
X203000Y75000D03*
X196497Y76502D03*
X200413Y433598D03*
X188413D03*
X192413D03*
X196413D03*
X210500Y30500D03*
X207880Y78740D03*
X214810Y78810D03*
X208300Y289500D03*
X217300D03*
X218500Y301700D03*
X213500D03*
X208500D03*
X209660Y331500D03*
X204413Y433598D03*
X208413D03*
X212413D03*
X216413D03*
X220413D03*
X232700Y29100D03*
X221800Y289500D03*
X222000Y330000D03*
X224413Y433598D03*
X228413D03*
X232413D03*
X236413D03*
X254527Y28900D03*
X244619D03*
X254527Y33900D03*
X240508Y76300D03*
Y66700D03*
X243822Y76300D03*
X253422D03*
X240508Y69900D03*
Y73100D03*
X240413Y433598D03*
X244413D03*
X248413D03*
X252413D03*
X264339Y32100D03*
X264304Y28900D03*
X272309D03*
X264339Y41700D03*
X263300Y52200D03*
X263507Y76300D03*
X256413Y433598D03*
X260413D03*
X264413D03*
X268413D03*
X272413D03*
X280087Y41700D03*
Y32100D03*
X280052Y28900D03*
X288057D03*
X288255Y76300D03*
X273107D03*
X278655D03*
X284500Y181100D03*
Y184300D03*
Y187500D03*
X283400Y198700D03*
X280200D03*
X277000D03*
X286600D03*
X284500Y190700D03*
X286151Y329500D03*
X289600Y330100D03*
X288413Y433598D03*
X284413D03*
X280413D03*
X276413D03*
X295835Y41700D03*
Y32100D03*
X295800Y28900D03*
X298726Y43529D03*
Y49471D03*
X307300Y61300D03*
X298700Y327000D03*
Y323500D03*
X293200Y329500D03*
X304413Y433598D03*
X300413D03*
X296413D03*
X292413D03*
X307708Y28900D03*
X321402Y54197D03*
X317402D03*
X310237Y89763D03*
X317025Y82975D03*
X319510Y190299D03*
X322200Y325000D03*
X310600Y330500D03*
X322200Y338500D03*
X324413Y433598D03*
X320413D03*
X316413D03*
X312413D03*
X308413D03*
X329402Y54197D03*
X325402D03*
X337402D03*
X341402D03*
X333402D03*
X338599Y108500D03*
X341799D03*
X337500Y113000D03*
Y122600D03*
Y116200D03*
Y119400D03*
X329110Y190299D03*
X340413Y433598D03*
X336413D03*
X332413D03*
X328413D03*
X345402Y54197D03*
X349402D03*
X353402D03*
X357402D03*
X349000Y82500D03*
X359300Y92000D03*
X348199Y108500D03*
X348264Y104707D03*
X357864D03*
X344999Y108500D03*
X351464Y104707D03*
X354664D03*
X352300Y175000D03*
X345301Y196299D03*
Y186699D03*
X358400Y182700D03*
X345930Y217000D03*
X354850Y276100D03*
X354800Y289800D03*
X355000Y332500D03*
Y328000D03*
X356413Y433598D03*
X352413D03*
X348413D03*
X344413D03*
X369402Y54197D03*
X373402D03*
X377402D03*
X361402D03*
X365402D03*
X373500Y78000D03*
X368900Y92000D03*
X373500Y94000D03*
X365101Y194759D03*
Y185159D03*
X375500Y350500D03*
X376413Y433598D03*
X372413D03*
X368413D03*
X364413D03*
X360413D03*
X381402Y54197D03*
X385402D03*
X389402D03*
X393402D03*
X379500Y72500D03*
X380500Y77400D03*
X380400Y81600D03*
X381700Y92400D03*
X390000Y100500D03*
X383128Y178372D03*
X383000Y346600D03*
X388500Y391000D03*
X393500D03*
X388500Y400000D03*
X393500D03*
X393000Y418500D03*
X392413Y433598D03*
X388413D03*
X384413D03*
X380413D03*
X397402Y54197D03*
X401402D03*
X405402D03*
X409402D03*
X396400Y100500D03*
X409200D03*
X398450Y116099D03*
X408050D03*
X401650D03*
X404850D03*
X405463Y383000D03*
X410463D03*
X398500Y391000D03*
Y400000D03*
X403000Y418500D03*
X398000D03*
X408413Y433598D03*
X404413D03*
X400413D03*
X396413D03*
X417402Y54197D03*
X421402D03*
X425402D03*
X429402D03*
X413402D03*
X413622Y75000D03*
X415463Y383000D03*
X414000Y419000D03*
X422337Y424000D03*
X416800D03*
X428413Y433598D03*
X424413D03*
X420413D03*
X416413D03*
X412413D03*
X433402Y54197D03*
X437402D03*
X441402D03*
X445402D03*
X444050Y116599D03*
X434450D03*
X437650D03*
X440850D03*
X446500Y289500D03*
X439500Y337892D03*
X442500Y336089D03*
X439500Y341500D03*
X443000Y386500D03*
Y401500D03*
Y396500D03*
X432000D03*
X444000Y416500D03*
X444413Y433598D03*
X440413D03*
X436413D03*
X432413D03*
X449402Y54197D03*
X453402D03*
X457402D03*
X461402D03*
X450930Y122167D03*
X460530D03*
X457330D03*
X454130D03*
X464413Y433598D03*
X460413D03*
X456413D03*
X452413D03*
X448413D03*
X465402Y54197D03*
X469402D03*
X473402D03*
X477402D03*
X481402D03*
X480413Y433598D03*
X476413D03*
X472413D03*
X468413D03*
X485402Y54197D03*
X489402D03*
X493402D03*
X497402D03*
X490970Y133500D03*
Y138500D03*
X488500Y359000D03*
X496413Y433598D03*
X492413D03*
X488413D03*
X484413D03*
X501402Y54197D03*
X505402D03*
X509402D03*
X513402D03*
X500500Y271100D03*
X500000Y278799D03*
X516413Y433598D03*
X512413D03*
X508413D03*
X504413D03*
X500413D03*
X517402Y54197D03*
X521402D03*
X525402D03*
X529402D03*
X533402D03*
X533000Y95000D03*
Y99500D03*
X522400Y270700D03*
X522600Y276200D03*
X528500Y299000D03*
X532300Y425700D03*
X532413Y433598D03*
X528413D03*
X524413D03*
X520413D03*
X537402Y54197D03*
X541402D03*
X545402D03*
X549402D03*
X549500Y69400D03*
X548158Y228033D03*
X545250Y256300D03*
X539977Y275124D03*
X540318Y270436D03*
X537500Y296607D03*
X548413Y433598D03*
X544413D03*
X540413D03*
X536413D03*
X553402Y54197D03*
X557402D03*
X561402D03*
X565402D03*
X568600Y76000D03*
X566600Y212900D03*
X553122Y227979D03*
X559500Y228000D03*
X566700Y227500D03*
X568413Y433598D03*
X564413D03*
X560413D03*
X556413D03*
X552413D03*
X569402Y54197D03*
X573402D03*
X577402D03*
X581402D03*
X585402D03*
X572500Y60301D03*
X572870Y67570D03*
X577100Y227900D03*
X581400Y262100D03*
Y272100D03*
Y282100D03*
X581500Y302100D03*
X584413Y433598D03*
X580413D03*
X576413D03*
X572413D03*
X589402Y54197D03*
X593402D03*
X597402D03*
X601402D03*
X597000Y199900D03*
X591902Y200300D03*
X601902Y200100D03*
X594153Y220500D03*
X589953Y236600D03*
X591000Y261500D03*
X590500Y301500D03*
X600413Y433598D03*
X596413D03*
X592413D03*
X588413D03*
X605402Y54197D03*
X609402D03*
X613402D03*
X617402D03*
X621402D03*
X606902Y200400D03*
X619961Y230874D03*
Y221274D03*
X620413Y433598D03*
X616413D03*
X612413D03*
X608413D03*
X604413D03*
X625402Y54197D03*
X629402D03*
X633500Y205906D03*
X625800Y215874D03*
X633000Y267000D03*
X636413Y433598D03*
X632413D03*
X628413D03*
X624413D03*
X649402Y54197D03*
X653402D03*
X656039Y57205D03*
Y61205D03*
Y65205D03*
Y69205D03*
Y73205D03*
Y77205D03*
Y81205D03*
Y85205D03*
Y89205D03*
Y93205D03*
Y97205D03*
Y101205D03*
Y105205D03*
Y109205D03*
Y113205D03*
Y117205D03*
Y121205D03*
Y125205D03*
Y129205D03*
Y145205D03*
Y133205D03*
Y137205D03*
Y141205D03*
Y149205D03*
Y153205D03*
Y157205D03*
Y161205D03*
Y165205D03*
Y169205D03*
Y173205D03*
Y177205D03*
Y181205D03*
Y235585D03*
Y311909D03*
Y315909D03*
Y319909D03*
Y323909D03*
Y327909D03*
Y331909D03*
Y335909D03*
Y339909D03*
Y343909D03*
Y347909D03*
Y351909D03*
Y355909D03*
Y359909D03*
Y363909D03*
Y367909D03*
Y371909D03*
Y375909D03*
Y379909D03*
Y383909D03*
Y387909D03*
Y391909D03*
Y395909D03*
Y399909D03*
Y403909D03*
Y407909D03*
Y411909D03*
Y415909D03*
Y419909D03*
Y423909D03*
Y427909D03*
Y431909D03*
X652413Y433598D03*
X648413D03*
X644413D03*
X640413D03*
G54D13*
X9000Y279000D03*
Y286000D03*
X17500Y91000D03*
X12500D03*
Y101000D03*
Y106000D03*
X19100Y148798D03*
X23600D03*
X28100D03*
X13620Y148720D03*
X13000Y157000D03*
X12500Y162000D03*
X17000Y204500D03*
X12500D03*
Y214500D03*
Y219500D03*
X19000Y262500D03*
X24200Y262508D03*
X28700D03*
X12500Y261500D03*
X19900Y283000D03*
X15000Y279000D03*
X28700Y274300D03*
X13000Y273327D03*
X16000Y302500D03*
X28500Y302000D03*
X28000Y296500D03*
X16000Y307500D03*
X18000Y314500D03*
X13000Y318700D03*
X28000Y327000D03*
X44500Y73500D03*
X45500Y104390D03*
Y126000D03*
X41500Y127500D03*
X41409Y132591D03*
X45500Y161000D03*
X41600Y148798D03*
X32600Y148700D03*
X37100Y148798D03*
X45500Y182500D03*
X45000Y213000D03*
X46000Y219500D03*
X42000Y236800D03*
X40500Y262000D03*
X33200Y262508D03*
X43000Y255500D03*
X29000Y291500D03*
X43000Y314500D03*
X33000D03*
X44500Y309000D03*
X39500D03*
X34500D03*
X35500Y327000D03*
X55500Y59000D03*
X50500Y60228D03*
X51772Y73600D03*
X47600Y68900D03*
X57000Y83500D03*
X51500D03*
X47000Y100000D03*
X61400Y104900D03*
X62500Y100500D03*
X57500Y101500D03*
X48390Y128312D03*
X53740Y126000D03*
X51772Y130500D03*
X55922Y140543D03*
X46500Y133000D03*
X47500Y140500D03*
X53900Y157000D03*
X60600Y161200D03*
X54130Y152500D03*
X60600Y157000D03*
X48957Y153619D03*
X51772Y187987D03*
X53500Y183500D03*
X54000Y213500D03*
X48000Y200500D03*
X53000D03*
X63000Y206000D03*
Y210500D03*
Y215000D03*
X49600Y213455D03*
X57500Y218500D03*
X51772Y245074D03*
X53200Y240187D03*
X48232Y264530D03*
X48500Y252500D03*
X55200Y253500D03*
X48500Y271500D03*
X52500Y278000D03*
X52800Y272000D03*
X57500Y289000D03*
X62000Y307000D03*
X61489Y332329D03*
X62000Y323500D03*
X55000Y336000D03*
Y355400D03*
X63500Y359600D03*
X67700Y65000D03*
X66400Y77400D03*
X71500Y77000D03*
X66000Y91100D03*
X76321Y78300D03*
X78500Y82250D03*
X69500Y100000D03*
X73500Y112500D03*
X67000Y109000D03*
X79000Y100500D03*
X74000D03*
X67500Y114500D03*
X68000Y119000D03*
X73500D03*
X69500Y130000D03*
X74000D03*
X75000Y141700D03*
X69000Y187500D03*
Y193000D03*
X69023Y198524D03*
X74593Y202207D03*
X71400Y221700D03*
X67500Y222900D03*
X67400Y227100D03*
X71400Y232900D03*
X71500Y247800D03*
X68000Y235500D03*
X67700Y240200D03*
X72400Y264600D03*
X80148Y253648D03*
X69500Y257800D03*
X64248Y258000D03*
X64500Y296750D03*
X78000Y291500D03*
X66000Y318500D03*
X79000Y315500D03*
X72000Y335000D03*
X66000Y323500D03*
X78635Y324492D03*
X79500Y341790D03*
Y348500D03*
X72000Y346300D03*
X66000Y419000D03*
X80500Y420500D03*
X88900Y67000D03*
X84200Y75000D03*
X83300Y87100D03*
X96500Y98000D03*
X92250Y97750D03*
X94500Y105000D03*
X89000Y110500D03*
X93500D03*
X90500Y105000D03*
X84000Y100500D03*
X87000Y130000D03*
Y120000D03*
X93500Y125000D03*
X87000Y125500D03*
X93500Y130000D03*
X86600Y141300D03*
X90500Y144500D03*
X95500Y145500D03*
X96500Y140000D03*
X91500D03*
X93900Y155200D03*
X95200Y151000D03*
X88500Y149000D03*
X94500Y163000D03*
X98500Y159000D03*
X91000Y181500D03*
X88250Y177250D03*
X83500Y178000D03*
X97500Y172000D03*
X98500Y165500D03*
X92000Y173000D03*
X83500D03*
X95500Y192000D03*
X83500Y193000D03*
Y188500D03*
X90500D03*
X94500Y197000D03*
X90500Y193500D03*
X85750Y202750D03*
X97500Y214000D03*
X84500Y218000D03*
X95700Y227500D03*
X98500Y218500D03*
X93032Y246477D03*
X96000Y241000D03*
X85700Y236500D03*
X96500Y235500D03*
X87200Y258300D03*
X98700Y268300D03*
X83200Y260300D03*
X86900Y267200D03*
X95900Y278900D03*
X94500Y312500D03*
X95000Y321500D03*
X95593Y333347D03*
X82500Y339000D03*
X82951Y327940D03*
X97500Y341000D03*
X95100Y351900D03*
X83000Y352500D03*
Y344500D03*
X95000D03*
X91500Y359500D03*
X83500Y360000D03*
X82800Y384600D03*
X94000Y420000D03*
X83000Y417000D03*
X103800Y76240D03*
X99000Y175500D03*
Y188500D03*
Y197500D03*
Y206500D03*
Y201500D03*
X98800Y272400D03*
X112500Y302000D03*
X107500D03*
X112500Y290000D03*
X102500D03*
Y302000D03*
X104500Y305500D03*
X105410Y318500D03*
X115253Y306247D03*
X99000Y350000D03*
X101500Y341000D03*
X104019Y347425D03*
X103000Y351500D03*
X113000Y344500D03*
X114000Y352000D03*
X103000Y364000D03*
X106500D03*
X110000D03*
X115500Y389000D03*
X104500Y377000D03*
X102500Y420000D03*
X119500Y57694D03*
X126000Y72000D03*
X127500Y290500D03*
X117500Y290000D03*
X125095Y306095D03*
X129000Y321500D03*
X126000Y318000D03*
X129500Y328000D03*
X123500Y347500D03*
X130000Y349664D03*
X119000Y352000D03*
X124500D03*
X120000Y364500D03*
X129000Y365000D03*
Y370500D03*
X120000Y368000D03*
Y371500D03*
X132000Y379000D03*
X118500D03*
X132000Y375500D03*
X127000Y397061D03*
X117000Y397000D03*
X121169Y396892D03*
X150860Y67400D03*
X145000Y296500D03*
X141000Y298500D03*
X135000Y312000D03*
X149500Y311034D03*
X140700Y320000D03*
X142130Y325630D03*
X146000Y334000D03*
X141916Y333916D03*
X140900Y355400D03*
X142000Y350000D03*
X148000Y370000D03*
X137000Y364000D03*
X145000Y359000D03*
X140123Y391604D03*
X135500Y383000D03*
Y390500D03*
X141000Y379500D03*
X148500Y380000D03*
X145000Y378000D03*
X140100Y395600D03*
X135500Y396000D03*
X135200Y408400D03*
X140000Y401000D03*
X135100Y412600D03*
X143500Y418000D03*
X151200Y75191D03*
X165000Y294000D03*
X166150Y304050D03*
X156800Y301100D03*
X156600Y295000D03*
X156000Y320500D03*
Y316500D03*
X166700Y338800D03*
X151000Y324200D03*
X156000Y325000D03*
Y329000D03*
X159100Y350400D03*
Y354600D03*
X166700Y343800D03*
X151500Y370000D03*
Y358000D03*
X159100Y382600D03*
X163600Y378600D03*
X157900Y387400D03*
X158500Y405200D03*
X160582Y410000D03*
X160550Y413400D03*
X151700Y411300D03*
X173170Y70840D03*
X168500Y294000D03*
X169850Y298950D03*
X179500Y294600D03*
X176500Y290000D03*
X178000Y309500D03*
X173800Y324100D03*
X178600Y378600D03*
Y374600D03*
X175100Y382600D03*
Y387100D03*
X174600Y401600D03*
Y406100D03*
X175000Y394500D03*
X177000Y398000D03*
X174600Y410600D03*
X176000Y416000D03*
X188900Y54960D03*
X192160Y77840D03*
X190000Y301500D03*
Y305500D03*
X189500Y319000D03*
X189000Y326000D03*
X191500Y413000D03*
X213500Y54000D03*
X208160Y73990D03*
X215000Y69000D03*
X220000D03*
X204770Y67780D03*
X207800Y83010D03*
X219200Y338800D03*
X205000Y348800D03*
Y353800D03*
X215000Y343800D03*
X219000Y348800D03*
X218000Y381100D03*
X219000Y392500D03*
X215500D03*
X216500Y396000D03*
X220000D03*
X217600Y415100D03*
X223500Y58250D03*
X231000Y68000D03*
Y71500D03*
X226500Y334000D03*
X222500Y324500D03*
X238000Y345000D03*
X225500Y347500D03*
X230000D03*
X228500Y382500D03*
X221500Y378500D03*
X226000D03*
X221500Y415000D03*
X225600Y415100D03*
X229500Y415000D03*
X254000Y213500D03*
X241441Y215000D03*
X241900Y238800D03*
X255400Y290100D03*
X247000Y344500D03*
X251000D03*
X255000D03*
X272330Y54871D03*
X259500Y54700D03*
Y70100D03*
X271000Y184500D03*
X269000Y215000D03*
X259000Y223000D03*
Y344500D03*
X282200Y179121D03*
X275260Y223000D03*
X280500Y224300D03*
X288000Y293000D03*
X288500Y317000D03*
X303500Y69400D03*
X307500Y160500D03*
X303500Y164000D03*
X298284Y175184D03*
X298500Y184500D03*
X300995Y187611D03*
X297772Y188694D03*
X292000Y294720D03*
X299500Y295500D03*
X301000Y312000D03*
X297000Y310500D03*
X301000Y317000D03*
X293700Y317300D03*
X312500Y160500D03*
X320500Y170000D03*
X311000Y193500D03*
X312000Y217000D03*
X308967Y204000D03*
X324000Y227500D03*
X312000Y234400D03*
X312500Y225400D03*
X311900Y229900D03*
X311600Y252400D03*
X312000Y269000D03*
Y256500D03*
Y264500D03*
X314500Y276500D03*
X312000Y295500D03*
X317500D03*
X321000D03*
X324500D03*
X310500Y321000D03*
X312500Y307500D03*
X321899Y343000D03*
X325000Y363000D03*
X320000Y398500D03*
X323000Y401500D03*
X321300Y423600D03*
X324800Y415200D03*
X321300Y416700D03*
X324800Y410700D03*
X336000Y61060D03*
X340500Y63500D03*
Y87000D03*
X338000Y102500D03*
X332550Y213550D03*
X341500Y233500D03*
X327923Y221577D03*
X335153Y217875D03*
X340953Y237000D03*
X328500Y258900D03*
X338500Y259000D03*
X330500Y291500D03*
X332500Y306500D03*
X328000D03*
X338000Y315000D03*
X341400Y323500D03*
X326000Y374000D03*
X340500Y361300D03*
X332500D03*
X336500D03*
X325300Y387200D03*
X331500Y376000D03*
X338500D03*
X342000D03*
X339200Y380300D03*
X339300Y384000D03*
Y387700D03*
X340500Y391600D03*
X325300Y396200D03*
Y391700D03*
X336300Y423200D03*
Y415200D03*
Y419200D03*
X340800Y415200D03*
X349500Y61000D03*
X354500Y60920D03*
X345500Y87000D03*
X354000Y82500D03*
X344000Y103000D03*
X354000Y128000D03*
X351000Y130500D03*
X353500D03*
X356000D03*
X347500Y141500D03*
X350000D03*
X352500D03*
X355000D03*
X357000Y154200D03*
X353482Y154157D03*
X350085Y154300D03*
X350100Y169400D03*
X352600D03*
X357600D03*
X355100D03*
X347300Y179000D03*
X346500Y174000D03*
X344500Y181500D03*
X351200Y196600D03*
X344000Y212000D03*
X350500Y229500D03*
X351000Y233243D03*
X355000Y242500D03*
X354975Y247900D03*
X351000Y237000D03*
X343500Y258900D03*
X357000Y295500D03*
X356000Y302300D03*
X349000Y303000D03*
X355500Y306500D03*
X346000D03*
X351000Y308000D03*
X355000Y337000D03*
X348418Y361300D03*
X344500D03*
X347700Y381600D03*
X347000Y391200D03*
X360000Y402400D03*
X359800Y397700D03*
X347600Y398800D03*
X348279Y405678D03*
X353000Y416500D03*
X350000Y419500D03*
X349500Y415000D03*
X346000Y416000D03*
X343700Y409900D03*
X348863Y410500D03*
X376838Y100230D03*
X367000Y126000D03*
X374300Y129000D03*
X371800D03*
X362000Y123500D03*
Y128000D03*
X374300Y132000D03*
X371800D03*
X360500Y154500D03*
X374900Y154228D03*
X371400Y154300D03*
X367900Y154228D03*
X363600Y176600D03*
X367600Y169300D03*
X364700Y169400D03*
X373649Y185735D03*
X369560Y213000D03*
X372060D03*
X367000D03*
X364500D03*
X367000Y232000D03*
X372500D03*
X360500Y243000D03*
X367000Y241243D03*
X373500Y247000D03*
X365500Y246500D03*
X369500Y267500D03*
X375800Y255200D03*
X376500Y269000D03*
X365000Y268000D03*
X362300Y286100D03*
X365800D03*
X370000Y276000D03*
X374500D03*
X374800Y291100D03*
X370300D03*
X361500Y296100D03*
X365800Y291100D03*
X362100Y291000D03*
X361400Y301500D03*
Y305800D03*
Y309900D03*
X365500Y305900D03*
X375500Y309200D03*
X371000Y326000D03*
X370000Y337000D03*
Y332500D03*
X366000Y350850D03*
X360700Y406200D03*
X363100Y418300D03*
X360311Y409880D03*
X363100Y422800D03*
X364500Y413500D03*
X382286Y86214D03*
X384000Y102980D03*
Y109500D03*
X378400Y154300D03*
X379800Y177100D03*
X380000Y204500D03*
X384091Y200091D03*
X379500Y237500D03*
X391900Y246800D03*
X386000D03*
X380100D03*
X386000Y259250D03*
X378000Y273500D03*
X389400Y281100D03*
X378000Y281000D03*
X382200D03*
X394800Y281300D03*
X388650Y292650D03*
X378000Y293200D03*
X383000D03*
X393300Y312500D03*
X383000Y323500D03*
X390000Y338500D03*
X392500Y329100D03*
Y323900D03*
X383000Y341500D03*
X384300Y368700D03*
X383900Y372600D03*
X381000Y365000D03*
X386500D03*
X389500Y370000D03*
X395000D03*
Y360000D03*
X383900Y384600D03*
X379500Y381000D03*
Y375800D03*
Y417500D03*
X407000Y120000D03*
X399500D03*
X399000Y221407D03*
Y225000D03*
X397800Y246800D03*
X403700D03*
X409300D03*
X397800Y259300D03*
X403700D03*
X400000Y265500D03*
X399800Y278400D03*
X409100Y281300D03*
X409300Y286300D03*
X402000Y303000D03*
X409200Y291700D03*
X396981Y304482D03*
X407500Y300500D03*
X402500Y308000D03*
X397500Y312900D03*
X407500Y305000D03*
X397300Y320700D03*
X408500Y316500D03*
Y321998D03*
Y311000D03*
X398000Y336500D03*
X410000Y338000D03*
X398000Y352000D03*
X406610Y353410D03*
X411840Y353620D03*
X410000Y358543D03*
X409000Y371339D03*
X409650Y403950D03*
X412350Y401250D03*
Y397150D03*
X409650Y394450D03*
X422000Y77500D03*
X423000Y72950D03*
X417500Y75000D03*
X413500Y88500D03*
X425000Y87700D03*
X423000Y100500D03*
X427800Y100300D03*
X429400Y107500D03*
X420900Y246800D03*
X415000D03*
X413000Y300500D03*
X429442Y310075D03*
X417500Y337000D03*
Y352000D03*
X422500Y354500D03*
X428500Y346000D03*
X413500Y373500D03*
X419000D03*
X420500Y366000D03*
X425000Y381000D03*
X420500D03*
X419150Y394450D03*
X416450Y401250D03*
Y397150D03*
X419150Y403950D03*
X423500Y415500D03*
X434500Y77000D03*
X441400Y78100D03*
X433500Y100500D03*
X444200D03*
X431000Y116500D03*
X444000Y226000D03*
X436500Y233000D03*
X443500Y231500D03*
X444000Y250000D03*
X436500Y237500D03*
X435000Y250500D03*
X443500Y236500D03*
X439500Y266500D03*
X444000Y263000D03*
X440000Y278500D03*
X434600Y278300D03*
X435500Y274500D03*
X445600Y278300D03*
X438150Y283800D03*
X447000Y283000D03*
X433050Y291400D03*
X446000Y294000D03*
X439000Y302000D03*
X434500D03*
X433000Y314320D03*
X435143Y306643D03*
X447000Y321998D03*
X440000Y332500D03*
X434000Y328000D03*
X447200Y347500D03*
X433000Y353500D03*
X433500Y366500D03*
X433382Y360466D03*
X438500Y364500D03*
X446000Y374500D03*
X438400Y382400D03*
X430000Y381000D03*
X431000Y406500D03*
Y416000D03*
Y411500D03*
X460000Y76000D03*
X448430Y89540D03*
X463500Y86500D03*
Y92000D03*
X458500Y86500D03*
X450000Y108200D03*
X454600Y108500D03*
X462000Y224500D03*
X461000Y234500D03*
X457500Y227500D03*
Y223500D03*
X449000Y232500D03*
Y227500D03*
X461000Y230000D03*
X462000Y250000D03*
X448500Y237500D03*
Y250000D03*
X457500Y237400D03*
X453000Y250000D03*
X457000Y258500D03*
X459500Y262000D03*
X461500Y268409D03*
X460000Y284500D03*
Y289500D03*
X460800Y294200D03*
X456500Y305500D03*
X454000Y312500D03*
X448500Y311500D03*
X461500Y311000D03*
X451000Y306500D03*
X459500Y322000D03*
X459000Y326000D03*
X450900Y330900D03*
X450500Y368500D03*
X453500Y381500D03*
X454000Y393500D03*
Y397000D03*
X450000Y407000D03*
Y416500D03*
Y411500D03*
X481000Y70700D03*
X478000Y78000D03*
X482000Y83500D03*
X465500Y78500D03*
X475500Y82500D03*
X470500D03*
X479867Y138867D03*
X481500Y182016D03*
X481000Y172500D03*
X479246Y178464D03*
X477500Y170500D03*
X478000Y198000D03*
X481500Y193000D03*
X480288Y203788D03*
X471000Y259200D03*
X477500Y259000D03*
X468500Y264500D03*
Y270000D03*
X471000Y347000D03*
X478500Y346000D03*
X481000Y341000D03*
X471400Y363300D03*
X470500Y391000D03*
X493700Y79161D03*
X496000Y85000D03*
X489400Y126300D03*
X493300Y121500D03*
X496000Y167500D03*
Y179258D03*
X484000Y166000D03*
X485033Y174934D03*
X498060Y185500D03*
X496500Y192500D03*
X483871Y198241D03*
X484000Y185500D03*
X497500Y214000D03*
X496000Y205500D03*
X492500Y226000D03*
X497500D03*
X497100Y244700D03*
X497200Y240600D03*
X492300Y240800D03*
X492500Y272200D03*
X491800Y277700D03*
X497000Y341000D03*
X495000Y346000D03*
X483501D03*
X488500D03*
X504000Y64500D03*
X508500D03*
X513200Y66000D03*
X503005Y99494D03*
X508000Y105500D03*
Y110500D03*
Y115500D03*
X503950Y143000D03*
X514500Y144000D03*
X503950Y133500D03*
X514500Y151000D03*
Y148000D03*
Y154000D03*
Y157000D03*
X501500Y192500D03*
X507000D03*
Y188500D03*
X515500Y201000D03*
X513000Y210500D03*
X511500Y206500D03*
X513500Y215500D03*
X509000D03*
X512100Y249500D03*
X507100Y240700D03*
X512100D03*
Y244700D03*
X502200Y240700D03*
X512100Y262500D03*
X512300Y254400D03*
X512200Y258700D03*
X512650Y268150D03*
X501000Y263500D03*
X511900Y276200D03*
X508950Y273250D03*
X506100Y280600D03*
X509000Y340500D03*
X504500D03*
X514000Y374000D03*
X505000Y379500D03*
X504500Y376000D03*
X507500Y394500D03*
X503500D03*
X521500Y60000D03*
X529500Y60500D03*
X519500Y75500D03*
X533000Y87000D03*
Y82000D03*
X519500Y81500D03*
X520000Y87000D03*
X524900Y99000D03*
X522500Y114500D03*
X533500Y124500D03*
X534000Y160500D03*
X517000Y212500D03*
X533200Y220000D03*
X529800Y223000D03*
X528710Y227500D03*
X534000Y231500D03*
X530350Y257480D03*
X532500Y272500D03*
X523600Y281100D03*
X531000Y285500D03*
X526000Y295500D03*
X532900Y318900D03*
X527600D03*
X519000Y307500D03*
X532400Y340600D03*
Y345600D03*
X527100Y340600D03*
Y345600D03*
X517500Y374000D03*
X532200Y377700D03*
X523700Y384100D03*
X528200Y377700D03*
X523700D03*
X518000Y382500D03*
X527500Y389100D03*
X525176Y411925D03*
X522100Y416500D03*
X543957Y60543D03*
X537000Y69000D03*
X549000Y63500D03*
X536500Y84500D03*
Y79000D03*
X534500Y130000D03*
Y136500D03*
X534600Y148300D03*
Y152000D03*
X544000Y159000D03*
X543520Y174970D03*
X542270Y169900D03*
X539770Y174900D03*
Y169900D03*
Y172400D03*
X542270D03*
X542500Y189500D03*
X538500D03*
X540900Y201500D03*
X543500Y205000D03*
X536900Y201500D03*
X545800Y216500D03*
X541000Y216400D03*
X537500Y232000D03*
X548300Y222600D03*
X546500Y240500D03*
X549000Y267500D03*
X551700Y256300D03*
X541000Y281500D03*
X539500Y292000D03*
X541346Y303507D03*
X542000Y296450D03*
X537500Y304000D03*
X538600Y318900D03*
X538100Y340600D03*
Y345600D03*
X539000Y370000D03*
X539300Y365100D03*
X539000Y360000D03*
X543000Y370000D03*
X543300Y365100D03*
X543000Y360000D03*
X548557Y387700D03*
X540600Y386300D03*
X538500Y407875D03*
X543000Y396700D03*
X548829Y416329D03*
X548500Y411000D03*
X538558Y413779D03*
X550369Y427558D03*
X538558D03*
X562500Y74600D03*
X560650Y70450D03*
X559941Y62120D03*
X563341Y62102D03*
X564350Y65350D03*
X559000Y85000D03*
X560200Y81500D03*
X559000Y88800D03*
X565933Y102000D03*
X562533Y102001D03*
X568700Y204300D03*
X564700Y204400D03*
X554600Y202400D03*
X558900Y202500D03*
X566950Y220000D03*
X553800Y240200D03*
X560000Y240000D03*
X565400Y244700D03*
X562000Y254870D03*
X554400Y267500D03*
X563700Y352400D03*
X568100Y366400D03*
Y361700D03*
X568326Y371200D03*
X563800Y390700D03*
X564500Y379000D03*
X560200Y386500D03*
X567500D03*
X568600Y376000D03*
Y380700D03*
X564400Y396700D03*
X567500Y403000D03*
X555000Y402000D03*
X567126Y417500D03*
X555315D03*
X562180Y413779D03*
Y427558D03*
X580500Y65800D03*
X580643Y60900D03*
X585900Y79600D03*
X586500Y107000D03*
Y112500D03*
X576459Y161971D03*
X575072Y165500D03*
X580500Y194500D03*
X583000Y192000D03*
X573200Y204300D03*
X586500Y230000D03*
X571000Y217900D03*
X576500Y219700D03*
X569943Y223300D03*
X578900Y236600D03*
X581500Y267000D03*
X581400Y292250D03*
X583000Y297000D03*
X580300Y356700D03*
X576300Y371200D03*
X580200Y361700D03*
X580100Y366700D03*
X580300Y380700D03*
Y375700D03*
Y385700D03*
Y390700D03*
X576900Y403100D03*
X578937Y417500D03*
X572500Y413500D03*
X584000Y421900D03*
X573991Y427558D03*
X599000Y92500D03*
X600850Y112350D03*
X592000Y136000D03*
Y141000D03*
Y146000D03*
Y163000D03*
Y151500D03*
Y157063D03*
Y173000D03*
Y178000D03*
Y168000D03*
X597703Y187000D03*
X587500Y190000D03*
X602500Y183000D03*
X601550Y208450D03*
X596450Y210350D03*
X601953Y218853D03*
X590650Y245680D03*
X604000Y254500D03*
X591000Y271500D03*
Y278500D03*
Y291500D03*
X602500Y404000D03*
X591000D03*
X604000Y398000D03*
X597500Y421900D03*
X602559Y417500D03*
X590748Y418725D03*
X597613Y413779D03*
Y427558D03*
X616500Y194874D03*
X606902Y186000D03*
X614100Y224100D03*
X610500Y227000D03*
X609500Y254500D03*
X614500Y403500D03*
X614370Y417500D03*
X609424Y413779D03*
Y427558D03*
X633500Y108000D03*
Y102000D03*
Y96500D03*
X622000Y136000D03*
Y141500D03*
Y146500D03*
Y162000D03*
Y151600D03*
Y157000D03*
Y181500D03*
Y175500D03*
X622035Y167063D03*
X633500Y196874D03*
X628500Y189500D03*
X636000Y216142D03*
X627500Y205374D03*
X626989Y237989D03*
X633000Y286500D03*
X633500Y301500D03*
X647000Y113500D03*
G54D15*
X19878Y36811D03*
X22704Y29987D03*
Y43635D03*
X19878Y373031D03*
X22704Y366207D03*
Y379855D03*
X29528Y27161D03*
X36352Y29987D03*
X39178Y36811D03*
X36352Y43635D03*
X29528Y46461D03*
Y363381D03*
X36352Y366207D03*
X39178Y373031D03*
X36352Y379855D03*
X29528Y382681D03*
X633215Y58530D03*
Y72178D03*
X630389Y65354D03*
X633215Y424659D03*
X630389Y417835D03*
X633215Y411011D03*
X640039Y55704D03*
X646863Y58530D03*
X649689Y65354D03*
X646863Y72178D03*
X640039Y75004D03*
Y408185D03*
X646863Y411011D03*
X649689Y417835D03*
X646863Y424659D03*
X640039Y427485D03*
G54D19*
X46000Y82000D03*
X51765Y96600D03*
X79500Y234500D03*
X79600Y248900D03*
X77964Y260100D03*
X75800Y274300D03*
X72000Y271400D03*
X82500Y230500D03*
X84600Y248900D03*
X89600D03*
X82500Y273200D03*
X87100Y271300D03*
X85800Y287452D03*
X112800Y66600D03*
X243500Y48650D03*
X252700Y44000D03*
X297700Y335100D03*
X324000Y236000D03*
X318000Y268500D03*
X324300Y254700D03*
X327500Y232000D03*
X332600Y246600D03*
X328500Y238645D03*
X327800Y246800D03*
X334350Y282000D03*
X336500Y295000D03*
X336525Y320500D03*
Y325500D03*
X341500Y338500D03*
Y328500D03*
Y333500D03*
X336525Y330500D03*
X342900Y246800D03*
X344000Y295000D03*
X358250Y340050D03*
X361124Y349876D03*
X387193Y143005D03*
X391130D03*
X387193Y150879D03*
X391130D03*
X387193Y158753D03*
X391130D03*
X387193Y166627D03*
X391130D03*
X391600Y304800D03*
X379300Y305000D03*
X383000Y328500D03*
Y333500D03*
X395067Y146942D03*
X399005D03*
X395067Y154816D03*
X399005D03*
X395067Y162690D03*
X399005D03*
X402942Y150879D03*
X406879D03*
X395067Y170564D03*
X399005D03*
X402942Y166627D03*
X406879D03*
X421360Y359970D03*
X446248Y143005D03*
Y186311D03*
X442311D03*
X441500Y297500D03*
X444000Y406500D03*
X431900Y392200D03*
X431169Y401169D03*
X444000Y411500D03*
X461996Y131193D03*
X450185Y143005D03*
X465933Y131193D03*
X473807Y135130D03*
Y139067D03*
Y146942D03*
X469870D03*
X470462Y369462D03*
X470500Y395000D03*
X493500Y359000D03*
X503000Y354600D03*
X550643Y400900D03*
X568000Y356700D03*
X555569Y388051D03*
G54D16*
X16039Y71260D03*
Y128346D03*
Y185433D03*
Y242520D03*
G54D20*
X63500Y84500D03*
X56500Y113000D03*
X54500Y171000D03*
X62000Y199500D03*
X57500Y226500D03*
X63600Y291500D03*
X75500Y62000D03*
X64400Y70000D03*
X64500Y129500D03*
X64700Y251700D03*
X79500Y308500D03*
X71000Y330500D03*
X78000D03*
X73500Y357500D03*
X70300D03*
X94500Y299000D03*
X88500Y303000D03*
X95000Y291500D03*
X87500Y295500D03*
X99500Y370000D03*
X110500Y382500D03*
X107300D03*
X153500Y310500D03*
X201700Y327900D03*
X229582Y48918D03*
X225000Y396000D03*
X250222Y76300D03*
X247022D03*
X264339Y35300D03*
Y38500D03*
X269907Y76300D03*
X266707D03*
X280087Y35300D03*
Y38500D03*
X285055Y76300D03*
X281855D03*
X295835Y35300D03*
Y38500D03*
Y44900D03*
Y48100D03*
X306500Y169500D03*
X314763Y85237D03*
X312500Y87500D03*
X322710Y190299D03*
X323500Y263000D03*
X324000Y301000D03*
X325910Y190299D03*
X338500Y213500D03*
X330500Y265000D03*
X337500D03*
X332000Y301500D03*
X337000Y344000D03*
X345301Y193099D03*
Y189899D03*
X344500Y265000D03*
X370500Y84000D03*
X365700Y92000D03*
X362500D03*
X374600Y178200D03*
X365101Y191559D03*
Y188359D03*
X375000Y210000D03*
X365500Y279500D03*
X369000Y413500D03*
X374500Y418500D03*
X387193Y135130D03*
X391130Y139067D03*
X387193D03*
Y146942D03*
X391130Y135130D03*
X387193Y154816D03*
Y162690D03*
Y170564D03*
X391130Y178437D03*
X387193D03*
X391130Y182374D03*
Y186311D03*
X385500Y196154D03*
X387193Y186311D03*
X380000Y210000D03*
X391130Y205996D03*
Y209933D03*
X387193D03*
X394000Y223500D03*
X383000Y232500D03*
X390000D03*
X387193Y217807D03*
X395000Y382000D03*
X395067Y139067D03*
X399005D03*
Y143005D03*
X402942D03*
Y146942D03*
X406879D03*
X410816D03*
Y135130D03*
X406879Y139067D03*
X402942D03*
X410811Y131188D03*
X406874D03*
X399000Y135125D03*
Y131188D03*
X395067Y135130D03*
X410816Y143005D03*
Y139067D03*
X406879Y143005D03*
X395067Y150879D03*
X402942Y154816D03*
X399005Y158753D03*
X410816D03*
X402942Y162690D03*
X410816D03*
Y150879D03*
Y154816D03*
X399005Y150879D03*
X402942Y158753D03*
X406879Y162690D03*
Y154816D03*
Y158753D03*
X395067Y166627D03*
X410816D03*
X402942Y170564D03*
X406879D03*
X395067Y178437D03*
X399005D03*
X410816D03*
Y170564D03*
X399005Y166627D03*
X406879Y178437D03*
X395067Y182374D03*
X399005Y186311D03*
Y190248D03*
X406879Y198122D03*
X399005Y182374D03*
X410816Y186311D03*
X395067Y194185D03*
X402942Y190248D03*
X406879Y182374D03*
Y186311D03*
Y194185D03*
X395067Y186311D03*
Y190248D03*
X402942Y182374D03*
X399005Y198122D03*
X395067D03*
X410816Y182374D03*
Y190248D03*
Y198122D03*
X402942Y186311D03*
Y194185D03*
X399005D03*
X402942Y198122D03*
X410816Y194185D03*
X406879Y190248D03*
X402942Y209933D03*
X399005Y202059D03*
X395067D03*
X402942Y205996D03*
X399005D03*
X406879Y202059D03*
X410816Y209933D03*
Y202059D03*
X399005Y209933D03*
X395067D03*
X406879Y205996D03*
Y209933D03*
X402942Y202059D03*
X395067Y205996D03*
X406879Y213870D03*
X408000Y327000D03*
X420500Y82000D03*
X429000Y123500D03*
X422000D03*
X418500Y117000D03*
X415000Y123500D03*
X414753Y131193D03*
X422627Y146942D03*
X426564Y135130D03*
X422627D03*
X418690D03*
X414753D03*
X422627Y131193D03*
X418690D03*
X426564Y146942D03*
Y143005D03*
Y131193D03*
Y139067D03*
X422627D03*
Y143005D03*
X418690D03*
X414753D03*
Y139067D03*
X418690Y146942D03*
X414753D03*
Y162690D03*
Y154816D03*
X418690Y158753D03*
X422627Y162690D03*
Y154816D03*
X426564Y162690D03*
Y158753D03*
X418690Y154816D03*
Y162690D03*
X414753Y158753D03*
X422627D03*
X426564Y154816D03*
X422627Y150879D03*
X418690D03*
X426564D03*
X418690Y166627D03*
X414753Y170564D03*
X422627D03*
X418690Y178437D03*
X426564Y166627D03*
Y178437D03*
X418690Y170564D03*
X414753Y166627D03*
X426564Y170564D03*
X422627Y190248D03*
X418690Y182374D03*
X426564Y186311D03*
Y190248D03*
X418690Y198122D03*
X422627Y194185D03*
Y186311D03*
Y182374D03*
X426564D03*
X414753Y190248D03*
X418690D03*
Y186311D03*
X414753D03*
Y182374D03*
Y198122D03*
X426564Y194185D03*
X422627Y198122D03*
X418690Y194185D03*
X414753Y213870D03*
X418690Y202059D03*
Y205996D03*
X414753D03*
Y209933D03*
X418690Y213870D03*
X414753Y202059D03*
X426564D03*
Y205996D03*
Y209933D03*
X422627Y202059D03*
Y205996D03*
X418690Y209933D03*
X425400Y229600D03*
X420500Y229500D03*
X414900Y229800D03*
X426564Y217807D03*
X423000Y235400D03*
X416100D03*
X429000Y274000D03*
X442311Y139067D03*
Y143005D03*
Y146942D03*
X438374Y135130D03*
X434437Y146942D03*
X438374D03*
X446248Y139067D03*
X445939Y135439D03*
X438374Y143005D03*
Y139067D03*
X434437D03*
Y135130D03*
Y131193D03*
X446248Y158753D03*
X442311Y162690D03*
X434437D03*
Y154816D03*
X438374Y162690D03*
Y150879D03*
Y158753D03*
X442311Y154816D03*
X434437Y158753D03*
X442311D03*
X438374Y154816D03*
X446248D03*
Y162690D03*
X434437Y150879D03*
X442311D03*
X446248D03*
X438374Y166627D03*
X446248D03*
X434437Y170564D03*
X442311D03*
X446248Y178437D03*
X434437Y166627D03*
X438374Y178437D03*
Y170564D03*
X442311Y166627D03*
X446248Y182374D03*
X442311D03*
X438374Y194185D03*
Y190248D03*
X434437Y186311D03*
Y190248D03*
Y194185D03*
Y182374D03*
X438374Y198122D03*
X442311Y190248D03*
Y194185D03*
X434437Y198122D03*
X446248D03*
X438374Y182374D03*
Y186311D03*
X446248Y194185D03*
X442311Y198122D03*
X434437Y205996D03*
X446248Y209933D03*
X438374D03*
Y205996D03*
Y202059D03*
X442311Y209933D03*
X434437Y202059D03*
Y213870D03*
X442311Y205996D03*
X446248D03*
Y202059D03*
X434437Y209933D03*
X438374Y217807D03*
X434437D03*
X430000Y386500D03*
X454122Y143005D03*
X457844Y131408D03*
X454122Y139067D03*
X458059D03*
X461996Y135130D03*
X454122D03*
X457844Y135345D03*
X449876Y131502D03*
X454122Y131193D03*
X458059Y146942D03*
X461996D03*
X450185D03*
X454122D03*
X458059Y143005D03*
X461996D03*
X450185Y139067D03*
X461996Y162690D03*
X458059Y158753D03*
X450185Y154816D03*
X461996Y158753D03*
X450185Y162690D03*
X454122Y158753D03*
Y162690D03*
X450185Y158753D03*
X458059Y162690D03*
X454122Y150879D03*
X461996D03*
X454122Y154816D03*
X458059D03*
X461996D03*
X450185Y150879D03*
X458059Y178437D03*
Y166627D03*
X450185Y170564D03*
X454123D03*
X454122Y166627D03*
X450185D03*
X454122Y178437D03*
X461996Y170564D03*
Y178437D03*
X458060Y170564D03*
X461996Y166627D03*
X450185Y182374D03*
X454122Y186311D03*
X450185Y198122D03*
X458059Y190248D03*
X454122Y182374D03*
X461996Y186311D03*
X458059Y182374D03*
X454122Y194185D03*
X450185D03*
X454122Y190248D03*
X458059Y186311D03*
X454122Y198122D03*
X458059D03*
X461996Y190248D03*
Y198122D03*
Y194185D03*
X450185Y186311D03*
Y190248D03*
X461996Y202059D03*
X458059Y213870D03*
X461996Y209933D03*
Y205996D03*
Y213870D03*
X458059Y202059D03*
Y205996D03*
X454122Y209933D03*
X458059D03*
X450185D03*
Y213870D03*
X454122D03*
X450185Y202059D03*
X454122D03*
X450185Y205996D03*
X454122Y217807D03*
X461996D03*
X458059D03*
X479500Y92500D03*
X466500Y110400D03*
X471200Y115700D03*
X481600Y125800D03*
X476800Y120700D03*
X465933Y146942D03*
X469870Y135130D03*
X465933Y139067D03*
X469870D03*
Y131193D03*
X473807D03*
X465933Y135130D03*
Y143005D03*
X469870D03*
X473807Y154816D03*
X465933Y162690D03*
X473807Y150879D03*
X465933Y154816D03*
X475000Y163000D03*
X465933Y158753D03*
Y150879D03*
X469870D03*
Y178437D03*
X473807Y166627D03*
X465933Y170564D03*
Y178437D03*
X469870Y166627D03*
Y170564D03*
X473807D03*
Y178437D03*
X465933Y190248D03*
Y194185D03*
Y186311D03*
X469870Y190248D03*
X473807Y182374D03*
X469870D03*
X465933D03*
X469870Y186311D03*
X473807Y190248D03*
X469870Y194185D03*
X465933Y198122D03*
X482000Y212500D03*
X473807Y205996D03*
X469870Y213870D03*
Y209933D03*
X465933Y202059D03*
Y205996D03*
X473807Y213870D03*
X469870Y205996D03*
X473807Y209933D03*
X469870Y217807D03*
X473807D03*
X467000Y355500D03*
X482800Y110300D03*
X483000Y133000D03*
X485000Y154000D03*
X497500Y148500D03*
X491000Y154000D03*
X491500Y148500D03*
X497000Y154000D03*
X483100Y272800D03*
X503000Y155000D03*
X503500Y149000D03*
X534500Y253600D03*
X530000Y406500D03*
X541000Y96000D03*
X540600Y234600D03*
X558000Y161500D03*
X566000Y347000D03*
X560000Y401000D03*
X580000Y104800D03*
X576500Y98000D03*
X576000Y246500D03*
X571800Y396500D03*
X587000Y184000D03*
X595500Y239000D03*
X619961Y224474D03*
Y227674D03*
G54D29*
X640952Y201181D03*
Y220867D03*
G54D18*
X22834Y340080D03*
X26378D03*
X28150Y343150D03*
X24606D03*
X29922Y340080D03*
X33466D03*
X37010D03*
X40554D03*
X44098D03*
X45870Y343150D03*
X42326D03*
X38782D03*
X35238D03*
X31694D03*
G54D11*
X6039Y61260D03*
Y81260D03*
Y118346D03*
Y138346D03*
Y175433D03*
Y195433D03*
Y232520D03*
Y252520D03*
X26039Y61260D03*
Y81260D03*
Y118346D03*
Y138346D03*
Y175433D03*
Y195433D03*
Y232520D03*
Y252520D03*
G54D25*
X588779Y334449D03*
Y350984D03*
Y367519D03*
G54D22*
X126067Y104043D03*
Y184043D03*
Y264043D03*
X253967Y93443D03*
X265967D03*
X277867D03*
X286067Y104043D03*
Y264043D03*
G54D14*
X29528Y36811D03*
Y373031D03*
X640039Y65354D03*
Y417835D03*
G54D23*
X143567Y106043D03*
X146067Y268043D03*
X268567Y112143D03*
Y255943D03*
G54D27*
X634055Y334449D03*
Y367519D03*
G54D28*
X651582Y197244D03*
Y224804D03*
G54D17*
X24807Y335985D03*
Y347245D03*
X43705Y331655D03*
Y351576D03*
G54D24*
X255906Y309646D03*
Y412008D03*
X494094Y309646D03*
Y412008D03*
G54D26*
X605315Y334449D03*
Y350984D03*
Y367519D03*
%LPC*%
G75*
G54D30*
G01X136000Y-65500D02*
Y-158000D01*
X506000D01*
Y-65500D01*
X136000D01*
G01X316000D02*
Y-158000D01*
G54D21*
X88300Y163900D03*
X187598Y36900D03*
X189500Y33000D03*
X186000D03*
X187598Y28900D03*
X212800Y289500D03*
X224500Y302000D03*
X322200Y320500D03*
X310600Y335000D03*
X354800Y285600D03*
X391130Y146942D03*
Y162690D03*
Y154816D03*
Y170564D03*
X395067Y143005D03*
Y131193D03*
X406879Y135130D03*
X395067Y158753D03*
X402942Y178437D03*
X395067Y213870D03*
X410816Y205996D03*
X406879Y217807D03*
X418690Y139067D03*
X414753Y150879D03*
Y178437D03*
X422627Y166627D03*
Y178437D03*
X414753Y194185D03*
X426564Y198122D03*
X422627Y209933D03*
X434437Y143005D03*
X438374Y131193D03*
X446248Y146942D03*
X434437Y178437D03*
X446248Y170564D03*
X442311Y178437D03*
X446248Y190248D03*
X438374Y213870D03*
X442311Y202059D03*
X450185Y135130D03*
X461996Y139067D03*
X458059Y150879D03*
X450185Y178437D03*
X461996Y182374D03*
X458059Y194185D03*
X454122Y205996D03*
X450185Y217807D03*
X473807Y143005D03*
X469870Y154816D03*
X465933Y166627D03*
X473807Y186311D03*
X469870Y198122D03*
X465933Y209933D03*
X552000Y367597D03*
Y371141D03*
X555200Y367597D03*
Y371141D03*
X552000Y374684D03*
Y378227D03*
X555200D03*
Y374684D03*
X576200Y342500D03*
G54D12*
X11264Y152264D03*
X12500Y96000D03*
Y209500D03*
X11963Y266437D03*
X16000Y297500D03*
X24100Y310900D03*
X11976Y323524D03*
X37400Y282900D03*
X59600Y60200D03*
X60100Y73000D03*
X50500Y104800D03*
X59000Y96500D03*
X62500Y117000D03*
X60500Y152000D03*
X51400Y161600D03*
X58000Y213500D03*
X51452Y219900D03*
X54590Y266870D03*
X62500Y365000D03*
Y369000D03*
Y373000D03*
Y378000D03*
Y382000D03*
X60300Y407100D03*
Y401100D03*
Y395100D03*
Y413100D03*
X76400Y87200D03*
X64445Y168945D03*
X73000Y365000D03*
X69500D03*
X66000D03*
X66500Y382000D03*
X70500D03*
X80700Y399200D03*
Y404200D03*
X71300D03*
Y399200D03*
X76000D03*
Y404200D03*
X71300Y394200D03*
X76000D03*
X80700D03*
X64300Y407600D03*
Y401600D03*
Y395600D03*
X80700Y409200D03*
X76000D03*
X71300D03*
X64300Y413600D03*
X86000Y63100D03*
X82100Y79300D03*
X88400Y154900D03*
X98500Y256661D03*
X82800Y364600D03*
X94500Y373000D03*
Y369000D03*
Y364500D03*
X90500D03*
X86500D03*
X94500Y380500D03*
X94000Y384500D03*
X90500D03*
X86500D03*
X94500Y376500D03*
X97800Y391800D03*
X85400Y404200D03*
Y399200D03*
Y394200D03*
X96800Y408100D03*
X92800D03*
Y402100D03*
X96800D03*
Y396100D03*
X92800D03*
X85400Y409200D03*
X96800Y414100D03*
X92800D03*
X111330Y59810D03*
X99000Y260025D03*
X125000Y76500D03*
X140100Y306900D03*
X153270Y58400D03*
X160500Y75500D03*
Y71500D03*
X182600Y289500D03*
X195900Y332500D03*
X228500Y75500D03*
Y79000D03*
X249000Y290300D03*
X296400Y70200D03*
X309000Y164500D03*
X324000Y220750D03*
X311900Y243400D03*
X310600Y326000D03*
X333500Y258900D03*
X339500Y282000D03*
X341000Y304000D03*
X349128Y186628D03*
X355500Y218000D03*
Y220500D03*
Y225500D03*
Y223000D03*
X358000Y261500D03*
X352500Y260000D03*
X348500D03*
X357680Y271780D03*
X349000Y295500D03*
X369310Y109500D03*
X369172Y102828D03*
X376500Y141000D03*
X374000D03*
X367400Y174400D03*
X377500Y218500D03*
Y221000D03*
Y226500D03*
Y223500D03*
X379000Y141000D03*
X382000Y142000D03*
X407500Y225000D03*
X420900Y259000D03*
X424900Y284300D03*
X423900Y278500D03*
X424900Y292900D03*
X439500Y250000D03*
X448500Y100500D03*
X462500Y117000D03*
X457500Y250000D03*
X461000Y302500D03*
X464500Y298500D03*
X471000Y239000D03*
X477000D03*
X496000Y163000D03*
X497000Y175000D03*
X496500Y197500D03*
X485000Y202739D03*
X490500Y216750D03*
X503860Y124150D03*
X503900Y128690D03*
X526500Y67500D03*
X525400Y247000D03*
X522000D03*
X524300Y261700D03*
X523900Y257100D03*
X532100Y399000D03*
X527500Y397100D03*
Y393100D03*
X551500Y59597D03*
X544500Y79500D03*
X549000Y78223D03*
X544300Y87100D03*
X549400Y81600D03*
X553000Y108500D03*
X561700Y320300D03*
X556700D03*
X562500Y336100D03*
Y326100D03*
X562000Y331600D03*
X560000Y342100D03*
X585000Y226500D03*
X588000Y96500D03*
X592000Y127063D03*
X599500Y116500D03*
X594003Y187000D03*
X610500Y190500D03*
X614100Y236400D03*
X618650Y249300D03*
X614500Y398000D03*
X637900Y116900D03*
X622000Y127063D03*
X647000Y108000D03*
G54D31*
G01X329433Y-125500D02*
Y-133000D01*
X333167D01*
G01X340480D02*
Y-128000D01*
G01Y-128875D02*
X340107Y-128375D01*
X339547Y-128125D01*
X338893Y-128000D01*
X338240Y-128250D01*
X337680Y-128750D01*
X337307Y-129500D01*
X337120Y-130500D01*
X337307Y-131500D01*
X337680Y-132250D01*
X338240Y-132750D01*
X338893Y-133000D01*
X339547Y-132875D01*
X340107Y-132500D01*
X340480Y-132000D01*
G01X344340Y-135250D02*
X344900Y-135500D01*
X345647Y-135250D01*
X346113Y-134750D01*
X346487Y-134125D01*
X347047Y-132125D01*
X348260Y-128000D01*
G01X345273D02*
X347047Y-132125D01*
G01X352400Y-129625D02*
X355387D01*
X355107Y-128750D01*
X354640Y-128250D01*
X353987Y-128000D01*
X353333Y-128125D01*
X352773Y-128500D01*
X352400Y-129375D01*
X352213Y-130125D01*
Y-130875D01*
X352400Y-131625D01*
X352867Y-132375D01*
X353427Y-132875D01*
X354080Y-133000D01*
X354733Y-132750D01*
X355387Y-132000D01*
G01X359993Y-133000D02*
Y-128000D01*
G01Y-129000D02*
X360460Y-128500D01*
X360927Y-128125D01*
X361580Y-128000D01*
X362047Y-128125D01*
X362607Y-128500D01*
G01X368800Y-133250D02*
X368613Y-133125D01*
Y-132875D01*
X368800Y-132750D01*
X368987Y-132875D01*
Y-133125D01*
X368800Y-133250D01*
G01Y-129875D02*
X368613Y-129750D01*
Y-129500D01*
X368800Y-129375D01*
X368987Y-129500D01*
Y-129750D01*
X368800Y-129875D01*
G01X336747Y-120500D02*
Y-113000D01*
X338613D01*
X339360Y-113375D01*
X339920Y-113875D01*
X340387Y-114625D01*
X340760Y-115500D01*
X340853Y-116750D01*
X340760Y-118000D01*
X340387Y-118875D01*
X339920Y-119625D01*
X339360Y-120125D01*
X338613Y-120500D01*
X336747D01*
G01X347980D02*
Y-115500D01*
G01Y-116375D02*
X347607Y-115875D01*
X347047Y-115625D01*
X346393Y-115500D01*
X345740Y-115750D01*
X345180Y-116250D01*
X344807Y-117000D01*
X344620Y-118000D01*
X344807Y-119000D01*
X345180Y-119750D01*
X345740Y-120250D01*
X346393Y-120500D01*
X347047Y-120375D01*
X347607Y-120000D01*
X347980Y-119500D01*
G01X353800Y-113000D02*
Y-120500D01*
G01X352493Y-115500D02*
X355107D01*
G01X359900Y-117125D02*
X362887D01*
X362607Y-116250D01*
X362140Y-115750D01*
X361487Y-115500D01*
X360833Y-115625D01*
X360273Y-116000D01*
X359900Y-116875D01*
X359713Y-117625D01*
Y-118375D01*
X359900Y-119125D01*
X360367Y-119875D01*
X360927Y-120375D01*
X361580Y-120500D01*
X362233Y-120250D01*
X362887Y-119500D01*
G01X368800Y-120750D02*
X368613Y-120625D01*
Y-120375D01*
X368800Y-120250D01*
X368987Y-120375D01*
Y-120625D01*
X368800Y-120750D01*
G01Y-117375D02*
X368613Y-117250D01*
Y-117000D01*
X368800Y-116875D01*
X368987Y-117000D01*
Y-117250D01*
X368800Y-117375D01*
G01X382027Y-114250D02*
X382587Y-113500D01*
X383240Y-113125D01*
X383987Y-113000D01*
X384920Y-113250D01*
X385573Y-113875D01*
X385760Y-114625D01*
X385667Y-115375D01*
X385293Y-116000D01*
X383427Y-117250D01*
X382587Y-118125D01*
X382027Y-119375D01*
X381840Y-120500D01*
X385760D01*
G01X391300Y-113000D02*
X390553Y-113250D01*
X389993Y-113875D01*
X389620Y-114625D01*
X389340Y-115625D01*
X389247Y-116750D01*
X389340Y-117875D01*
X389620Y-118875D01*
X389993Y-119625D01*
X390553Y-120250D01*
X391300Y-120500D01*
X392047Y-120250D01*
X392607Y-119625D01*
X392980Y-118875D01*
X393260Y-117875D01*
X393353Y-116750D01*
X393260Y-115625D01*
X392980Y-114625D01*
X392607Y-113875D01*
X392047Y-113250D01*
X391300Y-113000D01*
G01X397027Y-114250D02*
X397587Y-113500D01*
X398240Y-113125D01*
X398987Y-113000D01*
X399920Y-113250D01*
X400573Y-113875D01*
X400760Y-114625D01*
X400667Y-115375D01*
X400293Y-116000D01*
X398427Y-117250D01*
X397587Y-118125D01*
X397027Y-119375D01*
X396840Y-120500D01*
X400760D01*
G01X404527Y-114250D02*
X405087Y-113500D01*
X405740Y-113125D01*
X406487Y-113000D01*
X407420Y-113250D01*
X408073Y-113875D01*
X408260Y-114625D01*
X408167Y-115375D01*
X407793Y-116000D01*
X405927Y-117250D01*
X405087Y-118125D01*
X404527Y-119375D01*
X404340Y-120500D01*
X408260D01*
G01X412587Y-118000D02*
X415013D01*
G01X421300Y-113000D02*
X420553Y-113250D01*
X419993Y-113875D01*
X419620Y-114625D01*
X419340Y-115625D01*
X419247Y-116750D01*
X419340Y-117875D01*
X419620Y-118875D01*
X419993Y-119625D01*
X420553Y-120250D01*
X421300Y-120500D01*
X422047Y-120250D01*
X422607Y-119625D01*
X422980Y-118875D01*
X423260Y-117875D01*
X423353Y-116750D01*
X423260Y-115625D01*
X422980Y-114625D01*
X422607Y-113875D01*
X422047Y-113250D01*
X421300Y-113000D01*
G01X427027Y-114250D02*
X427587Y-113500D01*
X428240Y-113125D01*
X428987Y-113000D01*
X429920Y-113250D01*
X430573Y-113875D01*
X430760Y-114625D01*
X430667Y-115375D01*
X430293Y-116000D01*
X428427Y-117250D01*
X427587Y-118125D01*
X427027Y-119375D01*
X426840Y-120500D01*
X430760D01*
G01X435087Y-118000D02*
X437513D01*
G01X442027Y-114250D02*
X442587Y-113500D01*
X443240Y-113125D01*
X443987Y-113000D01*
X444920Y-113250D01*
X445573Y-113875D01*
X445760Y-114625D01*
X445667Y-115375D01*
X445293Y-116000D01*
X443427Y-117250D01*
X442587Y-118125D01*
X442027Y-119375D01*
X441840Y-120500D01*
X445760D01*
G01X449247Y-119375D02*
X449807Y-120000D01*
X450460Y-120375D01*
X451300Y-120500D01*
X452140Y-120250D01*
X452793Y-119750D01*
X453260Y-118875D01*
X453353Y-117875D01*
X453167Y-116875D01*
X452700Y-116250D01*
X452047Y-115750D01*
X451393Y-115625D01*
X450740Y-115750D01*
X449900Y-116250D01*
X450180Y-113000D01*
X452700D01*
G01X336933Y-108000D02*
Y-100500D01*
X339267D01*
X340013Y-100875D01*
X340480Y-101375D01*
X340667Y-102375D01*
X340480Y-103375D01*
X339920Y-104000D01*
X339267Y-104375D01*
X336933D01*
G01X339267D02*
X340667Y-108000D01*
G01X344900Y-104625D02*
X347887D01*
X347607Y-103750D01*
X347140Y-103250D01*
X346487Y-103000D01*
X345833Y-103125D01*
X345273Y-103500D01*
X344900Y-104375D01*
X344713Y-105125D01*
Y-105875D01*
X344900Y-106625D01*
X345367Y-107375D01*
X345927Y-107875D01*
X346580Y-108000D01*
X347233Y-107750D01*
X347887Y-107000D01*
G01X352120Y-103000D02*
X353800Y-108000D01*
X355480Y-103000D01*
G01X368800Y-108250D02*
X368613Y-108125D01*
Y-107875D01*
X368800Y-107750D01*
X368987Y-107875D01*
Y-108125D01*
X368800Y-108250D01*
G01Y-104875D02*
X368613Y-104750D01*
Y-104500D01*
X368800Y-104375D01*
X368987Y-104500D01*
Y-104750D01*
X368800Y-104875D01*
G01X383800Y-100500D02*
X383053Y-100750D01*
X382493Y-101375D01*
X382120Y-102125D01*
X381840Y-103125D01*
X381747Y-104250D01*
X381840Y-105375D01*
X382120Y-106375D01*
X382493Y-107125D01*
X383053Y-107750D01*
X383800Y-108000D01*
X384547Y-107750D01*
X385107Y-107125D01*
X385480Y-106375D01*
X385760Y-105375D01*
X385853Y-104250D01*
X385760Y-103125D01*
X385480Y-102125D01*
X385107Y-101375D01*
X384547Y-100750D01*
X383800Y-100500D01*
G01X391300Y-108000D02*
Y-100500D01*
X390180Y-102000D01*
G01Y-108000D02*
X392420D01*
G01X336933Y-95500D02*
Y-88000D01*
X339173D01*
X339920Y-88375D01*
X340480Y-89250D01*
X340667Y-90250D01*
X340480Y-91250D01*
X340013Y-92000D01*
X339173Y-92375D01*
X336933D01*
G01X344620Y-95750D02*
X347980Y-88000D01*
G01X351653Y-95500D02*
Y-88000D01*
X355947Y-95500D01*
Y-88000D01*
G01X368800Y-95750D02*
X368613Y-95625D01*
Y-95375D01*
X368800Y-95250D01*
X368987Y-95375D01*
Y-95625D01*
X368800Y-95750D01*
G01Y-92375D02*
X368613Y-92250D01*
Y-92000D01*
X368800Y-91875D01*
X368987Y-92000D01*
Y-92250D01*
X368800Y-92375D01*
G01X381933Y-95500D02*
Y-88000D01*
X384267D01*
X385013Y-88375D01*
X385480Y-88875D01*
X385667Y-89875D01*
X385480Y-90875D01*
X384920Y-91500D01*
X384267Y-91875D01*
X381933D01*
G01X384267D02*
X385667Y-95500D01*
G01X392420D02*
Y-88000D01*
X388967Y-93375D01*
X393633D01*
G01X398800Y-88000D02*
X398053Y-88250D01*
X397493Y-88875D01*
X397120Y-89625D01*
X396840Y-90625D01*
X396747Y-91750D01*
X396840Y-92875D01*
X397120Y-93875D01*
X397493Y-94625D01*
X398053Y-95250D01*
X398800Y-95500D01*
X399547Y-95250D01*
X400107Y-94625D01*
X400480Y-93875D01*
X400760Y-92875D01*
X400853Y-91750D01*
X400760Y-90625D01*
X400480Y-89625D01*
X400107Y-88875D01*
X399547Y-88250D01*
X398800Y-88000D01*
G01X406300D02*
X405553Y-88250D01*
X404993Y-88875D01*
X404620Y-89625D01*
X404340Y-90625D01*
X404247Y-91750D01*
X404340Y-92875D01*
X404620Y-93875D01*
X404993Y-94625D01*
X405553Y-95250D01*
X406300Y-95500D01*
X407047Y-95250D01*
X407607Y-94625D01*
X407980Y-93875D01*
X408260Y-92875D01*
X408353Y-91750D01*
X408260Y-90625D01*
X407980Y-89625D01*
X407607Y-88875D01*
X407047Y-88250D01*
X406300Y-88000D01*
G01X412027Y-92375D02*
X412680Y-91500D01*
X413240Y-91000D01*
X413987Y-90750D01*
X414640Y-91000D01*
X415107Y-91500D01*
X415480Y-92250D01*
X415573Y-93125D01*
X415480Y-93875D01*
X415107Y-94625D01*
X414547Y-95250D01*
X413893Y-95500D01*
X413147Y-95250D01*
X412493Y-94500D01*
X412120Y-93375D01*
X412027Y-92125D01*
X412213Y-90500D01*
X412493Y-89625D01*
X412960Y-88750D01*
X413613Y-88125D01*
X414267Y-88000D01*
X414920Y-88250D01*
X415387Y-88875D01*
G01X420087Y-93000D02*
X422513D01*
G01X429547Y-91500D02*
X429920Y-91125D01*
X430200Y-90500D01*
X430387Y-89625D01*
X430200Y-88875D01*
X429827Y-88375D01*
X429173Y-88000D01*
X426653D01*
Y-95500D01*
X429733D01*
X430387Y-95000D01*
X430760Y-94250D01*
X430947Y-93375D01*
X430760Y-92500D01*
X430200Y-91750D01*
X429547Y-91500D01*
X426653D01*
G01X436300Y-88000D02*
X435553Y-88250D01*
X434993Y-88875D01*
X434620Y-89625D01*
X434340Y-90625D01*
X434247Y-91750D01*
X434340Y-92875D01*
X434620Y-93875D01*
X434993Y-94625D01*
X435553Y-95250D01*
X436300Y-95500D01*
X437047Y-95250D01*
X437607Y-94625D01*
X437980Y-93875D01*
X438260Y-92875D01*
X438353Y-91750D01*
X438260Y-90625D01*
X437980Y-89625D01*
X437607Y-88875D01*
X437047Y-88250D01*
X436300Y-88000D01*
G01X443800D02*
X443053Y-88250D01*
X442493Y-88875D01*
X442120Y-89625D01*
X441840Y-90625D01*
X441747Y-91750D01*
X441840Y-92875D01*
X442120Y-93875D01*
X442493Y-94625D01*
X443053Y-95250D01*
X443800Y-95500D01*
X444547Y-95250D01*
X445107Y-94625D01*
X445480Y-93875D01*
X445760Y-92875D01*
X445853Y-91750D01*
X445760Y-90625D01*
X445480Y-89625D01*
X445107Y-88875D01*
X444547Y-88250D01*
X443800Y-88000D01*
G01X451300D02*
X450553Y-88250D01*
X449993Y-88875D01*
X449620Y-89625D01*
X449340Y-90625D01*
X449247Y-91750D01*
X449340Y-92875D01*
X449620Y-93875D01*
X449993Y-94625D01*
X450553Y-95250D01*
X451300Y-95500D01*
X452047Y-95250D01*
X452607Y-94625D01*
X452980Y-93875D01*
X453260Y-92875D01*
X453353Y-91750D01*
X453260Y-90625D01*
X452980Y-89625D01*
X452607Y-88875D01*
X452047Y-88250D01*
X451300Y-88000D01*
G01X458800Y-95500D02*
Y-88000D01*
X457680Y-89500D01*
G01Y-95500D02*
X459920D01*
G01X465087Y-93000D02*
X467513D01*
G01X473800Y-88000D02*
X473053Y-88250D01*
X472493Y-88875D01*
X472120Y-89625D01*
X471840Y-90625D01*
X471747Y-91750D01*
X471840Y-92875D01*
X472120Y-93875D01*
X472493Y-94625D01*
X473053Y-95250D01*
X473800Y-95500D01*
X474547Y-95250D01*
X475107Y-94625D01*
X475480Y-93875D01*
X475760Y-92875D01*
X475853Y-91750D01*
X475760Y-90625D01*
X475480Y-89625D01*
X475107Y-88875D01*
X474547Y-88250D01*
X473800Y-88000D01*
G01X479527Y-89250D02*
X480087Y-88500D01*
X480740Y-88125D01*
X481487Y-88000D01*
X482420Y-88250D01*
X483073Y-88875D01*
X483260Y-89625D01*
X483167Y-90375D01*
X482793Y-91000D01*
X480927Y-92250D01*
X480087Y-93125D01*
X479527Y-94375D01*
X479340Y-95500D01*
X483260D01*
G54D32*
G01X145964Y-110118D02*
G03I-634J0D01*
G01X149695D02*
G03I-1038J0D01*
G01X168013Y-137456D02*
G03I-634J0D01*
G01X155900Y-133655D02*
G03I-632J0D01*
G01X161735Y-128639D02*
G03I-1458J0D01*
G01X158530Y-131428D02*
G03I-1041J0D01*
G01X158461Y-119126D02*
G03I-1283J0D01*
G01X162690Y-117490D02*
G03I-1584J0D01*
G01X169809Y-121292D02*
G03I-2180J0D01*
G01X165531Y-125255D02*
G03I-1869J0D01*
G01X167813Y-115513D02*
G03I-1971J0D01*
G01X154775Y-120500D02*
G03I-892J0D01*
G01X162681Y-102774D02*
G03I-1584J0D01*
G01X158451Y-101149D02*
G03I-1283J0D01*
G01X159258Y-110118D02*
G03I-1868J0D01*
G01X169812Y-98951D02*
G03I-2180J0D01*
G01X167802Y-104739D02*
G03I-1971J0D01*
G01X165183Y-110118D02*
G03I-2180J0D01*
G01X171881D02*
G03I-2642J0D01*
G01X152135Y-98681D02*
G03I-632J0D01*
G01X154064Y-110118D02*
G03I-1460J0D01*
G01X154764Y-99775D02*
G03I-892J0D01*
G01X158530Y-88809D02*
G03I-1041J0D01*
G01X161742Y-91601D02*
G03I-1458J0D01*
G01X165531Y-94981D02*
G03I-1869J0D01*
G01X171080Y-131739D02*
G03I-1282J0D01*
G01X169322Y-135033D02*
G03I-892J0D01*
G01X180669Y-131528D02*
G03I-1870J0D01*
G01X180255Y-136311D02*
G03I-1456J0D01*
G01X179841Y-140261D02*
G03I-1042J0D01*
G01X179433Y-143587D02*
G03I-634J0D01*
G01X181439Y-119680D02*
G03I-2640J0D01*
G01X175373Y-123081D02*
G03I-1968J0D01*
G01X173018Y-127816D02*
G03I-1584J0D01*
G01X174681Y-116876D02*
G03I-2640J0D01*
G01X180979Y-125917D02*
G03I-2180J0D01*
G01X186177Y-123075D02*
G03I-1971J0D01*
G01X188199Y-116876D02*
G03I-2640J0D01*
G01X175452Y-97124D02*
G03I-1968J0D01*
G01X186225Y-97178D02*
G03I-1971J0D01*
G01X181439Y-100556D02*
G03I-2640J0D01*
G01X174681Y-103361D02*
G03I-2640J0D01*
G01X188199D02*
G03I-2640J0D01*
G01X179841Y-79975D02*
G03I-1042J0D01*
G01X171217Y-88444D02*
G03I-1282J0D01*
G01X173123Y-92378D02*
G03I-1584J0D01*
G01X180255Y-83924D02*
G03I-1456J0D01*
G01X180669Y-88708D02*
G03I-1870J0D01*
G01X180979Y-94320D02*
G03I-2180J0D01*
G01X179433Y-76648D02*
G03I-634J0D01*
G01X191096Y-134658D02*
G03I-892J0D01*
G01X192135Y-136781D02*
G03I-631J0D01*
G01X198775Y-128635D02*
G03I-1458J0D01*
G01X195808Y-125255D02*
G03I-1869J0D01*
G01X200547Y-113952D02*
G03X203345Y-117196I7247J3422D01*
G01X192148Y-121285D02*
G03I-2180J0D01*
G01X187928Y-127802D02*
G03I-1584J0D01*
G01X189667Y-131511D02*
G03I-1283J0D01*
G01X200699Y-105836D02*
G03X200547Y-113953I8974J-4228D01*
G01X208284Y-101612D02*
G03X200698Y-105835I-219J-8531D01*
G01X192148Y-98951D02*
G03I-2180J0D01*
G01X191108Y-82727D02*
G03I-634J0D01*
G01X190184Y-85250D02*
G03I-893J0D01*
G01X195808Y-94981D02*
G03I-1869J0D01*
G01X187839Y-92457D02*
G03I-1584J0D01*
G01X189190Y-88538D02*
G03I-1283J0D01*
G01X214259Y-115661D02*
G03X213314Y-114453I-714J415D01*
G01X202049Y-108260D02*
G03X205722Y-116181I7039J-1548D01*
G01X218075Y-112869D02*
G03X219083Y-115752I4343J-99D01*
G01X208854Y-116658D02*
G03X213313Y-114452I-2485J10632D01*
G01X208470Y-118462D02*
G03X214261Y-115663I-1122J9711D01*
G01X203346Y-117195D02*
G03X208470Y-118461I4545J7394D01*
G01X205721Y-116179D02*
G03X208853Y-116659I2561J6250D01*
G01X215903Y-114020D02*
G03X219079Y-118061I6190J1597D01*
G01X215904Y-114020D02*
Y-111835D01*
G01X227413Y-112869D02*
X218074D01*
G01X214175Y-103951D02*
G03X208283Y-101613I-6403J-7542D01*
G01X213150Y-105147D02*
G03X214175Y-103951I410J686D01*
G01X213152Y-105146D02*
G03X208030Y-103430I-5122J-6786D01*
G01X208029Y-103429D02*
G03X202049Y-108259I-48J-6058D01*
G01X225189Y-111399D02*
G03X218071I-3559J159D01*
G01X218070Y-111418D02*
Y-111399D01*
G01X225188Y-111418D02*
X218070D01*
G01X227412Y-111835D02*
G03X215906I-5753J223D01*
G01X230059Y-117625D02*
Y-102034D01*
G01X230060Y-117626D02*
G03X232080I1010J239D01*
G01X226590Y-116472D02*
G03X225311Y-115210I-817J451D01*
G01X234673Y-114020D02*
G03X237849Y-118061I6190J1597D01*
G01X232081Y-102041D02*
Y-117625D01*
G01X219083Y-115753D02*
G03X225311Y-115211I2844J3371D01*
G01X219079Y-118060D02*
G03X226591Y-116473I2662J5972D01*
G01X227413Y-111835D02*
Y-112869D01*
G01X232080Y-102041D02*
G03X230060Y-102034I-1011J-236D01*
G01X225188Y-111399D02*
Y-111418D01*
G01X234675Y-114020D02*
Y-111835D01*
G01X246181D02*
G03X234675I-5753J223D01*
G01X252849Y-116771D02*
G03X254892Y-115895I-74J2994D01*
G01X236844Y-112869D02*
G03X237852Y-115752I4343J-99D01*
G01X237848Y-118060D02*
G03X245360Y-116473I2662J5972D01*
G01X245358Y-116472D02*
G03X244079Y-115210I-817J451D01*
G01X237852Y-115753D02*
G03X244080Y-115211I2844J3371D01*
G01X249566Y-115529D02*
G03X252307Y-116760I2985J2980D01*
G01Y-116761D02*
G03X252849Y-116772I366J4691D01*
G01X250282Y-118087D02*
G03X254318Y-118340I2605J9244D01*
G01X247897Y-116444D02*
G03X250283Y-118086I3752J2898D01*
G01X249568Y-115529D02*
G03X247898Y-116443I-748J-616D01*
G01X255608Y-108618D02*
G03X253612Y-107689I-3116J-4086D01*
G01X246181Y-111835D02*
Y-112869D01*
G01D02*
X236844D01*
G01X255002Y-114328D02*
G03X252723Y-112986I-3540J-3405D01*
G01X249955Y-112030D02*
G03X252723Y-112985I8208J19302D01*
G01X243957Y-111399D02*
Y-111418D01*
G01X243958Y-111399D02*
G03X236840I-3559J159D01*
G01X236841Y-111418D02*
Y-111399D01*
G01X243957Y-111418D02*
X236841D01*
G01X248537Y-109748D02*
G03X249956Y-112031I2652J66D01*
G01X248537Y-108250D02*
Y-109748D01*
G01X250179Y-106359D02*
G03X248537Y-108249I2747J-4045D01*
G01X256884Y-107368D02*
G03X250178Y-106359I-4153J-4811D01*
G01X253611Y-107689D02*
G03X251080Y-107949I-869J-3992D01*
G01X251081Y-107948D02*
G03X250837Y-110104I805J-1183D01*
G01Y-110106D02*
G03X254306Y-111513I5270J8013D01*
G01X260954Y-116041D02*
Y-107954D01*
G01X254892Y-115895D02*
G03X255001Y-114328I-764J840D01*
G01X269619Y-117484D02*
Y-106797D01*
G01X269620Y-117484D02*
G03X271926I1153J198D01*
G01X266864Y-117375D02*
G03X266002Y-116329I-764J249D01*
G01X262978Y-115462D02*
G03X266002Y-116329I2046J1428D01*
G01X260955Y-116043D02*
G03X264164Y-118351I2956J725D01*
G01X265463Y-118350D02*
X264165D01*
G01X265464Y-118352D02*
G03X266864Y-117374I-24J1525D01*
G01X256906Y-116470D02*
G03X257054Y-113728I-3143J1545D01*
G01X254317Y-118340D02*
G03X256906Y-116470I-1259J4470D01*
G01X262978Y-107954D02*
Y-115463D01*
G01X257054Y-113729D02*
G03X254307Y-111513I-3470J-1490D01*
G01X271969Y-102342D02*
G03I-1194J0D01*
G01X271926Y-106797D02*
G03X269620I-1153J-409D01*
G01X266003Y-107954D02*
X262978D01*
G01X266004Y-107955D02*
G03X266008Y-105932I-177J1012D01*
G01X262978D02*
X266008D01*
G01X262971Y-103419D02*
X262978Y-105932D01*
G01X262972Y-103418D02*
G03X260954Y-103491I-1005J-141D01*
G01Y-105932D02*
Y-103492D01*
G01X259930Y-105932D02*
X260954D01*
G01X259930D02*
G03X259981Y-107955I298J-1005D01*
G01X260954Y-107954D02*
X259982D01*
G01X255606Y-108620D02*
G03X256885Y-107367I599J667D01*
G01X290671Y-110842D02*
G03X290703Y-118351I860J-3751D01*
G01X276837Y-114305D02*
G03X278891Y-116297I4069J2141D01*
G01X274529Y-113568D02*
G03X275888Y-116443I5718J944D01*
G01X275887D02*
G03X279572Y-118352I4392J3967D01*
G01X281425Y-118350D02*
X279571D01*
G01X281425D02*
G03X284525Y-117161I0J4636D01*
G01X285201Y-116508D02*
X284524Y-117161D01*
G01X285201Y-116508D02*
G03X283966Y-115211I-695J574D01*
G01X281510Y-116675D02*
G03X283966Y-115212I-989J4453D01*
G01X278889Y-116297D02*
G03X281508Y-116677I1946J4197D01*
G01X271926Y-106797D02*
Y-117484D01*
G01X274529Y-113566D02*
Y-111839D01*
G01X276446Y-112943D02*
G03X276837Y-114305I4162J458D01*
G01X276445Y-112066D02*
Y-112943D01*
G01X283833Y-109274D02*
G03X285403Y-108106I585J852D01*
G01X285402D02*
G03X280919Y-105777I-4776J-3714D01*
G01X279541D02*
X280919D01*
G01X279540D02*
G03X274999Y-109274I1260J-6333D01*
G01X274998D02*
G03X274529Y-111839I9988J-3152D01*
G01X276849Y-109932D02*
G03X276446Y-112066I5467J-2137D01*
G01X280036Y-107542D02*
G03X276849Y-109933I664J-4205D01*
G01X282662Y-108199D02*
G03X280037Y-107539I-2313J-3650D01*
G01X283833Y-109275D02*
G03X282662Y-108202I-9277J-8949D01*
G01X294457Y-116619D02*
G03Y-112289I-51J2165D01*
G01X291853Y-116620D02*
X294456D01*
G01X291853Y-112289D02*
G03Y-116619I195J-2165D01*
G01X294165Y-118350D02*
X290701D01*
G01X294165D02*
G03X296471Y-117226I-1088J5161D01*
G01X296473Y-117625D02*
Y-117226D01*
G01X296474Y-117627D02*
G03X298494I1010J185D01*
G01X298495Y-109394D02*
Y-117625D01*
G01X301067Y-108534D02*
Y-106508D01*
G01X301615Y-108534D02*
X301067D01*
G01X301615Y-106508D02*
Y-108534D01*
G01X302461Y-106508D02*
X301615D01*
G01X302461Y-106001D02*
Y-106508D01*
G01X300223Y-106001D02*
X302461D01*
G01X300223Y-106508D02*
Y-106001D01*
G01X301067Y-106508D02*
X300223D01*
G01X305164Y-106001D02*
X304731D01*
G01X305713Y-108544D02*
X305164Y-106001D01*
G01X305171Y-108544D02*
X305713D01*
G01X304889Y-106871D02*
X305171Y-108544D01*
G01X304309D02*
X304889Y-106871D01*
G01X304086Y-108544D02*
X304309D01*
G01X303501Y-106887D02*
X304086Y-108544D01*
G01X303226D02*
X303501Y-106887D01*
G01X302698Y-108544D02*
X303226D01*
G01X303243Y-106001D02*
X302698Y-108544D01*
G01X303648Y-106001D02*
X303243D01*
G01X304192Y-107632D02*
X303648Y-106001D01*
G01X304731D02*
X304192Y-107632D01*
G01X294456Y-112288D02*
X291853D01*
G01X296473Y-110841D02*
Y-109686D01*
G01X296472Y-110841D02*
G03X292878Y-110536I-3256J-17043D01*
G01X292879Y-110535D02*
G03X290670Y-110842I280J-10112D01*
G01X298496Y-109394D02*
G03X295031Y-105933I-3962J-501D01*
G01X291563Y-105932D02*
X295031D01*
G01X291562D02*
G03X289112Y-107085I584J-4421D01*
G01Y-107086D02*
G03X289820Y-108520I585J-603D01*
G01X290987Y-107954D02*
G03X289821Y-108520I1446J-4464D01*
G01X294740Y-107954D02*
X290987D01*
G01X296473Y-109686D02*
G03X294742Y-107955I-1598J133D01*
G01X381000Y-125000D02*
Y-133000D01*
X385000D01*
G01X391000Y-125000D02*
X390200Y-125267D01*
X389600Y-125933D01*
X389200Y-126733D01*
X388900Y-127800D01*
X388800Y-129000D01*
X388900Y-130200D01*
X389200Y-131267D01*
X389600Y-132067D01*
X390200Y-132733D01*
X391000Y-133000D01*
X391800Y-132733D01*
X392400Y-132067D01*
X392800Y-131267D01*
X393100Y-130200D01*
X393200Y-129000D01*
X393100Y-127800D01*
X392800Y-126733D01*
X392400Y-125933D01*
X391800Y-125267D01*
X391000Y-125000D01*
G01X397100Y-129667D02*
X397800Y-128733D01*
X398400Y-128200D01*
X399200Y-127933D01*
X399900Y-128200D01*
X400400Y-128733D01*
X400800Y-129533D01*
X400900Y-130467D01*
X400800Y-131267D01*
X400400Y-132067D01*
X399800Y-132733D01*
X399100Y-133000D01*
X398300Y-132733D01*
X397600Y-131934D01*
X397200Y-130733D01*
X397100Y-129400D01*
X397300Y-127667D01*
X397600Y-126733D01*
X398100Y-125800D01*
X398800Y-125133D01*
X399500Y-125000D01*
X400200Y-125267D01*
X400700Y-125933D01*
G01X404000Y-135667D02*
X410000D01*
G01X412500Y-125000D02*
X415000Y-133000D01*
X417500Y-125000D01*
G01X425200Y-125667D02*
X424600Y-125267D01*
X423900Y-125000D01*
X423100D01*
X422200Y-125400D01*
X421500Y-126067D01*
X421000Y-126867D01*
X420600Y-128200D01*
X420500Y-129400D01*
X420700Y-130600D01*
X421000Y-131400D01*
X421600Y-132200D01*
X422300Y-132733D01*
X423000Y-133000D01*
X423700D01*
X424400Y-132733D01*
X425000Y-132333D01*
X425500Y-131800D01*
G01X433200Y-125667D02*
X432600Y-125267D01*
X431900Y-125000D01*
X431100D01*
X430200Y-125400D01*
X429500Y-126067D01*
X429000Y-126867D01*
X428600Y-128200D01*
X428500Y-129400D01*
X428700Y-130600D01*
X429000Y-131400D01*
X429600Y-132200D01*
X430300Y-132733D01*
X431000Y-133000D01*
X431700D01*
X432400Y-132733D01*
X433000Y-132333D01*
X433500Y-131800D01*
G01X437100Y-126333D02*
X437700Y-125533D01*
X438400Y-125133D01*
X439200Y-125000D01*
X440200Y-125267D01*
X440900Y-125933D01*
X441100Y-126733D01*
X441000Y-127534D01*
X440600Y-128200D01*
X438600Y-129533D01*
X437700Y-130467D01*
X437100Y-131800D01*
X436900Y-133000D01*
X441100D01*
M02*
